FILE_TYPE = MACRO_DRAWING;
SET COLOR_WIRE YELLOW;
SET COLOR_PROP ORANGE;
SET COLOR_DOT WHITE;
SET COLOR_ARC YELLOW;
SET COLOR_BODY GREEN;
SET COLOR_NOTE PURPLE;
SET PROP_DISPLAY VALUE;
SET PAGE_NUMBER P354;
FORCEADD OFFPAGE..1
(1700 3600);
FORCEPROP 2 LAST $XR0 52 
J 0
(1479 3600);
DISPLAY 0.638298 (1479 3600);
PAINT MONO (1479 3600);
FORCEPROP 2 LAST CDS_LIB standard
J 0
(1700 3600);
DISPLAY INVISIBLE (1700 3600);
FORCEPROP 1 LAST OFFPAGE TRUE
J 0
(2025 3475);
DISPLAY 0.872340 (2025 3475);
DISPLAY INVISIBLE (2025 3475);
FORCEPROP 1 LAST COMMENT_BODY TRUE
J 0
(1825 3500);
DISPLAY 0.872340 (1825 3500);
PAINT GREEN (1825 3500);
DISPLAY INVISIBLE (1825 3500);
FORCEPROP 2 LAST PATH I107
J 0
(1750 3675);
DISPLAY 1.021277 (1750 3675);
DISPLAY INVISIBLE (1750 3675);
FORCEADD OFFPAGE..1
(1700 3650);
FORCEPROP 2 LAST $XR0 52 
J 0
(1479 3650);
DISPLAY 0.638298 (1479 3650);
PAINT MONO (1479 3650);
FORCEPROP 2 LAST CDS_LIB standard
J 0
(1700 3650);
DISPLAY INVISIBLE (1700 3650);
FORCEPROP 1 LAST OFFPAGE TRUE
J 0
(2025 3525);
DISPLAY 0.872340 (2025 3525);
DISPLAY INVISIBLE (2025 3525);
FORCEPROP 1 LAST COMMENT_BODY TRUE
J 0
(1825 3550);
DISPLAY 0.872340 (1825 3550);
PAINT GREEN (1825 3550);
DISPLAY INVISIBLE (1825 3550);
FORCEPROP 2 LAST PATH I108
J 0
(1750 3725);
DISPLAY 1.021277 (1750 3725);
DISPLAY INVISIBLE (1750 3725);
FORCEADD TAP..1
R 2
(2650 200);
FORCEPROP 3 LASTPIN (2700 200) SIG_NAME P5E_CPU1_P2_TX_DP<0>
J 0
(2710 210);
DISPLAY 0.659574 (2710 210);
PAINT MONO (2710 210);
DISPLAY INVISIBLE (2710 210);
FORCEPROP 1 LASTPIN (2700 200) BN 0
J 2
(2712 208);
DISPLAY 0.680851 (2712 208);
PAINT GREEN (2712 208);
FORCEPROP 2 LAST CDS_LIB standard
J 0
(2650 200);
DISPLAY INVISIBLE (2650 200);
FORCEPROP 1 LAST BODY_TYPE PLUMBING
J 2
(2650 250);
DISPLAY 0.872340 (2650 250);
PAINT GREEN (2650 250);
DISPLAY INVISIBLE (2650 250);
FORCEPROP 1 LAST HDL_TAP TRUE
J 2
(2325 75);
DISPLAY 0.872340 (2325 75);
DISPLAY INVISIBLE (2325 75);
FORCEPROP 1 LAST PATH I109
J 2
(2652 200);
DISPLAY 0.872340 (2652 200);
PAINT GREEN (2652 200);
DISPLAY INVISIBLE (2652 200);
FORCEADD TAP..1
R 2
(2650 400);
FORCEPROP 3 LASTPIN (2700 400) SIG_NAME P5E_CPU1_P2_TX_DP<1>
J 0
(2710 410);
DISPLAY 0.659574 (2710 410);
PAINT MONO (2710 410);
DISPLAY INVISIBLE (2710 410);
FORCEPROP 1 LASTPIN (2700 400) BN 1
J 2
(2712 408);
DISPLAY 0.680851 (2712 408);
PAINT GREEN (2712 408);
FORCEPROP 2 LAST CDS_LIB standard
J 0
(2650 400);
DISPLAY INVISIBLE (2650 400);
FORCEPROP 1 LAST BODY_TYPE PLUMBING
J 2
(2650 450);
DISPLAY 0.872340 (2650 450);
PAINT GREEN (2650 450);
DISPLAY INVISIBLE (2650 450);
FORCEPROP 1 LAST HDL_TAP TRUE
J 2
(2325 275);
DISPLAY 0.872340 (2325 275);
DISPLAY INVISIBLE (2325 275);
FORCEPROP 1 LAST PATH I110
J 2
(2652 400);
DISPLAY 0.872340 (2652 400);
PAINT GREEN (2652 400);
DISPLAY INVISIBLE (2652 400);
FORCEADD TAP..1
R 2
(2650 600);
FORCEPROP 3 LASTPIN (2700 600) SIG_NAME P5E_CPU1_P2_TX_DP<2>
J 0
(2710 610);
DISPLAY 0.659574 (2710 610);
PAINT MONO (2710 610);
DISPLAY INVISIBLE (2710 610);
FORCEPROP 1 LASTPIN (2700 600) BN 2
J 2
(2712 608);
DISPLAY 0.680851 (2712 608);
PAINT GREEN (2712 608);
FORCEPROP 2 LAST CDS_LIB standard
J 0
(2650 600);
DISPLAY INVISIBLE (2650 600);
FORCEPROP 1 LAST BODY_TYPE PLUMBING
J 2
(2650 650);
DISPLAY 0.872340 (2650 650);
PAINT GREEN (2650 650);
DISPLAY INVISIBLE (2650 650);
FORCEPROP 1 LAST HDL_TAP TRUE
J 2
(2325 475);
DISPLAY 0.872340 (2325 475);
DISPLAY INVISIBLE (2325 475);
FORCEPROP 1 LAST PATH I111
J 2
(2652 600);
DISPLAY 0.872340 (2652 600);
PAINT GREEN (2652 600);
DISPLAY INVISIBLE (2652 600);
FORCEADD TAP..1
R 2
(2650 800);
FORCEPROP 3 LASTPIN (2700 800) SIG_NAME P5E_CPU1_P2_TX_DP<3>
J 0
(2710 810);
DISPLAY 0.659574 (2710 810);
PAINT MONO (2710 810);
DISPLAY INVISIBLE (2710 810);
FORCEPROP 1 LASTPIN (2700 800) BN 3
J 2
(2712 808);
DISPLAY 0.680851 (2712 808);
PAINT GREEN (2712 808);
FORCEPROP 2 LAST CDS_LIB standard
J 0
(2650 800);
DISPLAY INVISIBLE (2650 800);
FORCEPROP 1 LAST BODY_TYPE PLUMBING
J 2
(2650 850);
DISPLAY 0.872340 (2650 850);
PAINT GREEN (2650 850);
DISPLAY INVISIBLE (2650 850);
FORCEPROP 1 LAST HDL_TAP TRUE
J 2
(2325 675);
DISPLAY 0.872340 (2325 675);
DISPLAY INVISIBLE (2325 675);
FORCEPROP 1 LAST PATH I112
J 2
(2652 800);
DISPLAY 0.872340 (2652 800);
PAINT GREEN (2652 800);
DISPLAY INVISIBLE (2652 800);
FORCEADD TAP..1
R 2
(2650 1000);
FORCEPROP 3 LASTPIN (2700 1000) SIG_NAME P5E_CPU1_P2_TX_DP<4>
J 0
(2710 1010);
DISPLAY 0.659574 (2710 1010);
PAINT MONO (2710 1010);
DISPLAY INVISIBLE (2710 1010);
FORCEPROP 1 LASTPIN (2700 1000) BN 4
J 2
(2712 1008);
DISPLAY 0.680851 (2712 1008);
PAINT GREEN (2712 1008);
FORCEPROP 2 LAST CDS_LIB standard
J 0
(2650 1000);
DISPLAY INVISIBLE (2650 1000);
FORCEPROP 1 LAST BODY_TYPE PLUMBING
J 2
(2650 1050);
DISPLAY 0.872340 (2650 1050);
PAINT GREEN (2650 1050);
DISPLAY INVISIBLE (2650 1050);
FORCEPROP 1 LAST HDL_TAP TRUE
J 2
(2325 875);
DISPLAY 0.872340 (2325 875);
DISPLAY INVISIBLE (2325 875);
FORCEPROP 1 LAST PATH I113
J 2
(2652 1000);
DISPLAY 0.872340 (2652 1000);
PAINT GREEN (2652 1000);
DISPLAY INVISIBLE (2652 1000);
FORCEADD TAP..1
R 2
(2650 1200);
FORCEPROP 3 LASTPIN (2700 1200) SIG_NAME P5E_CPU1_P2_TX_DP<5>
J 0
(2710 1210);
DISPLAY 0.659574 (2710 1210);
PAINT MONO (2710 1210);
DISPLAY INVISIBLE (2710 1210);
FORCEPROP 1 LASTPIN (2700 1200) BN 5
J 2
(2712 1208);
DISPLAY 0.680851 (2712 1208);
PAINT GREEN (2712 1208);
FORCEPROP 2 LAST CDS_LIB standard
J 0
(2650 1200);
DISPLAY INVISIBLE (2650 1200);
FORCEPROP 1 LAST BODY_TYPE PLUMBING
J 2
(2650 1250);
DISPLAY 0.872340 (2650 1250);
PAINT GREEN (2650 1250);
DISPLAY INVISIBLE (2650 1250);
FORCEPROP 1 LAST HDL_TAP TRUE
J 2
(2325 1075);
DISPLAY 0.872340 (2325 1075);
DISPLAY INVISIBLE (2325 1075);
FORCEPROP 1 LAST PATH I114
J 2
(2652 1200);
DISPLAY 0.872340 (2652 1200);
PAINT GREEN (2652 1200);
DISPLAY INVISIBLE (2652 1200);
FORCEADD TAP..1
R 2
(2650 1400);
FORCEPROP 3 LASTPIN (2700 1400) SIG_NAME P5E_CPU1_P2_TX_DP<6>
J 0
(2710 1410);
DISPLAY 0.659574 (2710 1410);
PAINT MONO (2710 1410);
DISPLAY INVISIBLE (2710 1410);
FORCEPROP 1 LASTPIN (2700 1400) BN 6
J 2
(2712 1408);
DISPLAY 0.680851 (2712 1408);
PAINT GREEN (2712 1408);
FORCEPROP 2 LAST CDS_LIB standard
J 0
(2650 1400);
DISPLAY INVISIBLE (2650 1400);
FORCEPROP 1 LAST BODY_TYPE PLUMBING
J 2
(2650 1450);
DISPLAY 0.872340 (2650 1450);
PAINT GREEN (2650 1450);
DISPLAY INVISIBLE (2650 1450);
FORCEPROP 1 LAST HDL_TAP TRUE
J 2
(2325 1275);
DISPLAY 0.872340 (2325 1275);
DISPLAY INVISIBLE (2325 1275);
FORCEPROP 1 LAST PATH I115
J 2
(2652 1400);
DISPLAY 0.872340 (2652 1400);
PAINT GREEN (2652 1400);
DISPLAY INVISIBLE (2652 1400);
FORCEADD TAP..1
R 2
(2650 1600);
FORCEPROP 3 LASTPIN (2700 1600) SIG_NAME P5E_CPU1_P2_TX_DP<7>
J 0
(2710 1610);
DISPLAY 0.659574 (2710 1610);
PAINT MONO (2710 1610);
DISPLAY INVISIBLE (2710 1610);
FORCEPROP 1 LASTPIN (2700 1600) BN 7
J 2
(2712 1608);
DISPLAY 0.680851 (2712 1608);
PAINT GREEN (2712 1608);
FORCEPROP 2 LAST CDS_LIB standard
J 0
(2650 1600);
DISPLAY INVISIBLE (2650 1600);
FORCEPROP 1 LAST BODY_TYPE PLUMBING
J 2
(2650 1650);
DISPLAY 0.872340 (2650 1650);
PAINT GREEN (2650 1650);
DISPLAY INVISIBLE (2650 1650);
FORCEPROP 1 LAST HDL_TAP TRUE
J 2
(2325 1475);
DISPLAY 0.872340 (2325 1475);
DISPLAY INVISIBLE (2325 1475);
FORCEPROP 1 LAST PATH I116
J 2
(2652 1600);
DISPLAY 0.872340 (2652 1600);
PAINT GREEN (2652 1600);
DISPLAY INVISIBLE (2652 1600);
FORCEADD TAP..1
R 2
(2900 250);
FORCEPROP 3 LASTPIN (2950 250) SIG_NAME P5E_CPU1_P2_TX_DN<0>
J 0
(2960 260);
DISPLAY 0.659574 (2960 260);
PAINT MONO (2960 260);
DISPLAY INVISIBLE (2960 260);
FORCEPROP 1 LASTPIN (2950 250) BN 0
J 2
(2962 258);
DISPLAY 0.680851 (2962 258);
PAINT GREEN (2962 258);
FORCEPROP 2 LAST CDS_LIB standard
J 0
(2900 250);
DISPLAY INVISIBLE (2900 250);
FORCEPROP 1 LAST BODY_TYPE PLUMBING
J 2
(2900 300);
DISPLAY 0.872340 (2900 300);
PAINT GREEN (2900 300);
DISPLAY INVISIBLE (2900 300);
FORCEPROP 1 LAST HDL_TAP TRUE
J 2
(2575 125);
DISPLAY 0.872340 (2575 125);
DISPLAY INVISIBLE (2575 125);
FORCEPROP 1 LAST PATH I117
J 2
(2902 250);
DISPLAY 0.872340 (2902 250);
PAINT GREEN (2902 250);
DISPLAY INVISIBLE (2902 250);
FORCEADD TAP..1
R 2
(2900 450);
FORCEPROP 3 LASTPIN (2950 450) SIG_NAME P5E_CPU1_P2_TX_DN<1>
J 0
(2960 460);
DISPLAY 0.659574 (2960 460);
PAINT MONO (2960 460);
DISPLAY INVISIBLE (2960 460);
FORCEPROP 1 LASTPIN (2950 450) BN 1
J 2
(2962 458);
DISPLAY 0.680851 (2962 458);
PAINT GREEN (2962 458);
FORCEPROP 2 LAST CDS_LIB standard
J 0
(2900 450);
DISPLAY INVISIBLE (2900 450);
FORCEPROP 1 LAST BODY_TYPE PLUMBING
J 2
(2900 500);
DISPLAY 0.872340 (2900 500);
PAINT GREEN (2900 500);
DISPLAY INVISIBLE (2900 500);
FORCEPROP 1 LAST HDL_TAP TRUE
J 2
(2575 325);
DISPLAY 0.872340 (2575 325);
DISPLAY INVISIBLE (2575 325);
FORCEPROP 1 LAST PATH I118
J 2
(2902 450);
DISPLAY 0.872340 (2902 450);
PAINT GREEN (2902 450);
DISPLAY INVISIBLE (2902 450);
FORCEADD TAP..1
R 2
(2900 650);
FORCEPROP 3 LASTPIN (2950 650) SIG_NAME P5E_CPU1_P2_TX_DN<2>
J 0
(2960 660);
DISPLAY 0.659574 (2960 660);
PAINT MONO (2960 660);
DISPLAY INVISIBLE (2960 660);
FORCEPROP 1 LASTPIN (2950 650) BN 2
J 2
(2962 658);
DISPLAY 0.680851 (2962 658);
PAINT GREEN (2962 658);
FORCEPROP 2 LAST CDS_LIB standard
J 0
(2900 650);
DISPLAY INVISIBLE (2900 650);
FORCEPROP 1 LAST BODY_TYPE PLUMBING
J 2
(2900 700);
DISPLAY 0.872340 (2900 700);
PAINT GREEN (2900 700);
DISPLAY INVISIBLE (2900 700);
FORCEPROP 1 LAST HDL_TAP TRUE
J 2
(2575 525);
DISPLAY 0.872340 (2575 525);
DISPLAY INVISIBLE (2575 525);
FORCEPROP 1 LAST PATH I119
J 2
(2902 650);
DISPLAY 0.872340 (2902 650);
PAINT GREEN (2902 650);
DISPLAY INVISIBLE (2902 650);
FORCEADD TAP..1
R 2
(2900 850);
FORCEPROP 3 LASTPIN (2950 850) SIG_NAME P5E_CPU1_P2_TX_DN<3>
J 0
(2960 860);
DISPLAY 0.659574 (2960 860);
PAINT MONO (2960 860);
DISPLAY INVISIBLE (2960 860);
FORCEPROP 1 LASTPIN (2950 850) BN 3
J 2
(2962 858);
DISPLAY 0.680851 (2962 858);
PAINT GREEN (2962 858);
FORCEPROP 2 LAST CDS_LIB standard
J 0
(2900 850);
DISPLAY INVISIBLE (2900 850);
FORCEPROP 1 LAST BODY_TYPE PLUMBING
J 2
(2900 900);
DISPLAY 0.872340 (2900 900);
PAINT GREEN (2900 900);
DISPLAY INVISIBLE (2900 900);
FORCEPROP 1 LAST HDL_TAP TRUE
J 2
(2575 725);
DISPLAY 0.872340 (2575 725);
DISPLAY INVISIBLE (2575 725);
FORCEPROP 1 LAST PATH I120
J 2
(2902 850);
DISPLAY 0.872340 (2902 850);
PAINT GREEN (2902 850);
DISPLAY INVISIBLE (2902 850);
FORCEADD TAP..1
R 2
(2900 1050);
FORCEPROP 3 LASTPIN (2950 1050) SIG_NAME P5E_CPU1_P2_TX_DN<4>
J 0
(2960 1060);
DISPLAY 0.659574 (2960 1060);
PAINT MONO (2960 1060);
DISPLAY INVISIBLE (2960 1060);
FORCEPROP 1 LASTPIN (2950 1050) BN 4
J 2
(2962 1058);
DISPLAY 0.680851 (2962 1058);
PAINT GREEN (2962 1058);
FORCEPROP 2 LAST CDS_LIB standard
J 0
(2900 1050);
DISPLAY INVISIBLE (2900 1050);
FORCEPROP 1 LAST BODY_TYPE PLUMBING
J 2
(2900 1100);
DISPLAY 0.872340 (2900 1100);
PAINT GREEN (2900 1100);
DISPLAY INVISIBLE (2900 1100);
FORCEPROP 1 LAST HDL_TAP TRUE
J 2
(2575 925);
DISPLAY 0.872340 (2575 925);
DISPLAY INVISIBLE (2575 925);
FORCEPROP 1 LAST PATH I121
J 2
(2902 1050);
DISPLAY 0.872340 (2902 1050);
PAINT GREEN (2902 1050);
DISPLAY INVISIBLE (2902 1050);
FORCEADD Q_CAP_DIFFBUS..2
R 2
(3625 200);
FORCEPROP 1 LAST LOCATION C773
J 2
(3859 217);
DISPLAY 0.723404 (3859 217);
PAINT GREEN (3859 217);
FORCEPROP 2 LAST $SEC 1
J 2
(3800 275);
DISPLAY 0.680851 (3800 275);
PAINT MONO (3800 275);
DISPLAY INVISIBLE (3800 275);
FORCEPROP 2 LAST CDS_SEC 1
J 2
(3800 275);
DISPLAY 0.680851 (3800 275);
DISPLAY INVISIBLE (3800 275);
FORCEPROP 2 LASTPIN (3700 200) $PN 1
J 0
(3710 210);
DISPLAY 0.808511 (3710 210);
FORCEPROP 2 LASTPIN (3550 200) $PN 2
J 2
(3540 210);
DISPLAY 0.808511 (3540 210);
FORCEPROP 2 LAST VALUE DIFF BUS_0.22UF
J 2
(3475 200);
DISPLAY 0.553191 (3475 200);
FORCEPROP 1 LAST PIN_NAMES_ROTATE TRUE
J 2
(3625 200);
DISPLAY 0.489362 (3625 200);
PAINT GREEN (3625 200);
DISPLAY INVISIBLE (3625 200);
FORCEPROP 2 LAST CDS_LIB pure_quanta
J 2
(3625 200);
DISPLAY INVISIBLE (3625 200);
FORCEPROP 1 LAST CDS_LMAN_SYM_OUTLINE -25,50,25,-50
J 2
(3625 200);
DISPLAY 0.468085 (3625 200);
PAINT GREEN (3625 200);
DISPLAY INVISIBLE (3625 200);
FORCEPROP 2 LAST VOLTAGE 6.3V
J 2
(3275 250);
DISPLAY 0.553191 (3275 250);
DISPLAY INVISIBLE (3275 250);
FORCEPROP 1 LAST MATERIAL X6S
J 2
(3634 279);
DISPLAY 0.574468 (3634 279);
PAINT GREEN (3634 279);
DISPLAY INVISIBLE (3634 279);
FORCEPROP 2 LAST PACK_TYPE C0201
J 2
(3450 250);
DISPLAY 0.553191 (3450 250);
DISPLAY INVISIBLE (3450 250);
FORCEPROP 2 LAST TOLERANCE 20%
J 2
(3550 250);
DISPLAY 0.553191 (3550 250);
DISPLAY INVISIBLE (3550 250);
FORCEPROP 1 LAST PART_NUMBER SP_CH4221MEE01
J 2
(3509 288);
DISPLAY 0.574468 (3509 288);
PAINT GREEN (3509 288);
DISPLAY INVISIBLE (3509 288);
FORCEPROP 1 LAST LOCATION C773
J 0
(3875 275);
DISPLAY 1.021277 (3875 275);
DISPLAY INVISIBLE (3875 275);
FORCEPROP 1 LAST PATH I122
J 2
(3625 200);
DISPLAY 0.723404 (3625 200);
DISPLAY INVISIBLE (3625 200);
FORCEADD Q_CAP_DIFFBUS..2
R 2
(3625 250);
FORCEPROP 1 LAST LOCATION C772
J 2
(3859 267);
DISPLAY 0.723404 (3859 267);
PAINT GREEN (3859 267);
FORCEPROP 2 LAST $SEC 1
J 2
(3800 325);
DISPLAY 0.680851 (3800 325);
PAINT MONO (3800 325);
DISPLAY INVISIBLE (3800 325);
FORCEPROP 2 LAST CDS_SEC 1
J 2
(3800 325);
DISPLAY 0.680851 (3800 325);
DISPLAY INVISIBLE (3800 325);
FORCEPROP 2 LASTPIN (3700 250) $PN 1
J 0
(3710 260);
DISPLAY 0.808511 (3710 260);
FORCEPROP 2 LASTPIN (3550 250) $PN 2
J 2
(3540 260);
DISPLAY 0.808511 (3540 260);
FORCEPROP 2 LAST VALUE DIFF BUS_0.22UF
J 2
(3475 250);
DISPLAY 0.553191 (3475 250);
FORCEPROP 1 LAST PIN_NAMES_ROTATE TRUE
J 2
(3625 250);
DISPLAY 0.489362 (3625 250);
PAINT GREEN (3625 250);
DISPLAY INVISIBLE (3625 250);
FORCEPROP 2 LAST CDS_LIB pure_quanta
J 2
(3625 250);
DISPLAY INVISIBLE (3625 250);
FORCEPROP 1 LAST CDS_LMAN_SYM_OUTLINE -25,50,25,-50
J 2
(3625 250);
DISPLAY 0.468085 (3625 250);
PAINT GREEN (3625 250);
DISPLAY INVISIBLE (3625 250);
FORCEPROP 2 LAST VOLTAGE 6.3V
J 2
(3275 300);
DISPLAY 0.553191 (3275 300);
DISPLAY INVISIBLE (3275 300);
FORCEPROP 1 LAST MATERIAL X6S
J 2
(3634 329);
DISPLAY 0.574468 (3634 329);
PAINT GREEN (3634 329);
DISPLAY INVISIBLE (3634 329);
FORCEPROP 2 LAST PACK_TYPE C0201
J 2
(3450 300);
DISPLAY 0.553191 (3450 300);
DISPLAY INVISIBLE (3450 300);
FORCEPROP 2 LAST TOLERANCE 20%
J 2
(3550 300);
DISPLAY 0.553191 (3550 300);
DISPLAY INVISIBLE (3550 300);
FORCEPROP 1 LAST PART_NUMBER SP_CH4221MEE01
J 2
(3509 338);
DISPLAY 0.574468 (3509 338);
PAINT GREEN (3509 338);
DISPLAY INVISIBLE (3509 338);
FORCEPROP 1 LAST LOCATION C772
J 0
(3875 325);
DISPLAY 1.021277 (3875 325);
DISPLAY INVISIBLE (3875 325);
FORCEPROP 1 LAST PATH I123
J 2
(3625 250);
DISPLAY 0.723404 (3625 250);
DISPLAY INVISIBLE (3625 250);
FORCEADD Q_CAP_DIFFBUS..2
R 2
(3625 400);
FORCEPROP 1 LAST LOCATION C771
J 2
(3859 417);
DISPLAY 0.723404 (3859 417);
PAINT GREEN (3859 417);
FORCEPROP 2 LAST $SEC 1
J 2
(3800 475);
DISPLAY 0.680851 (3800 475);
PAINT MONO (3800 475);
DISPLAY INVISIBLE (3800 475);
FORCEPROP 2 LAST CDS_SEC 1
J 2
(3800 475);
DISPLAY 0.680851 (3800 475);
DISPLAY INVISIBLE (3800 475);
FORCEPROP 2 LASTPIN (3700 400) $PN 1
J 0
(3710 410);
DISPLAY 0.808511 (3710 410);
FORCEPROP 2 LASTPIN (3550 400) $PN 2
J 2
(3540 410);
DISPLAY 0.808511 (3540 410);
FORCEPROP 2 LAST VALUE DIFF BUS_0.22UF
J 2
(3475 400);
DISPLAY 0.553191 (3475 400);
FORCEPROP 1 LAST PIN_NAMES_ROTATE TRUE
J 2
(3625 400);
DISPLAY 0.489362 (3625 400);
PAINT GREEN (3625 400);
DISPLAY INVISIBLE (3625 400);
FORCEPROP 2 LAST CDS_LIB pure_quanta
J 2
(3625 400);
DISPLAY INVISIBLE (3625 400);
FORCEPROP 1 LAST CDS_LMAN_SYM_OUTLINE -25,50,25,-50
J 2
(3625 400);
DISPLAY 0.468085 (3625 400);
PAINT GREEN (3625 400);
DISPLAY INVISIBLE (3625 400);
FORCEPROP 2 LAST VOLTAGE 6.3V
J 2
(3275 450);
DISPLAY 0.553191 (3275 450);
DISPLAY INVISIBLE (3275 450);
FORCEPROP 1 LAST MATERIAL X6S
J 2
(3634 479);
DISPLAY 0.574468 (3634 479);
PAINT GREEN (3634 479);
DISPLAY INVISIBLE (3634 479);
FORCEPROP 2 LAST PACK_TYPE C0201
J 2
(3450 450);
DISPLAY 0.553191 (3450 450);
DISPLAY INVISIBLE (3450 450);
FORCEPROP 2 LAST TOLERANCE 20%
J 2
(3550 450);
DISPLAY 0.553191 (3550 450);
DISPLAY INVISIBLE (3550 450);
FORCEPROP 1 LAST PART_NUMBER SP_CH4221MEE01
J 2
(3509 488);
DISPLAY 0.574468 (3509 488);
PAINT GREEN (3509 488);
DISPLAY INVISIBLE (3509 488);
FORCEPROP 1 LAST LOCATION C771
J 0
(3875 475);
DISPLAY 1.021277 (3875 475);
DISPLAY INVISIBLE (3875 475);
FORCEPROP 1 LAST PATH I124
J 2
(3625 400);
DISPLAY 0.723404 (3625 400);
DISPLAY INVISIBLE (3625 400);
FORCEADD Q_CAP_DIFFBUS..2
R 2
(3625 450);
FORCEPROP 1 LAST LOCATION C770
J 2
(3859 467);
DISPLAY 0.723404 (3859 467);
PAINT GREEN (3859 467);
FORCEPROP 2 LAST $SEC 1
J 2
(3800 525);
DISPLAY 0.680851 (3800 525);
PAINT MONO (3800 525);
DISPLAY INVISIBLE (3800 525);
FORCEPROP 2 LAST CDS_SEC 1
J 2
(3800 525);
DISPLAY 0.680851 (3800 525);
DISPLAY INVISIBLE (3800 525);
FORCEPROP 2 LASTPIN (3700 450) $PN 1
J 0
(3710 460);
DISPLAY 0.808511 (3710 460);
FORCEPROP 2 LASTPIN (3550 450) $PN 2
J 2
(3540 460);
DISPLAY 0.808511 (3540 460);
FORCEPROP 2 LAST VALUE DIFF BUS_0.22UF
J 2
(3475 450);
DISPLAY 0.553191 (3475 450);
FORCEPROP 1 LAST PIN_NAMES_ROTATE TRUE
J 2
(3625 450);
DISPLAY 0.489362 (3625 450);
PAINT GREEN (3625 450);
DISPLAY INVISIBLE (3625 450);
FORCEPROP 1 LAST CDS_LMAN_SYM_OUTLINE -25,50,25,-50
J 2
(3625 450);
DISPLAY 0.468085 (3625 450);
PAINT GREEN (3625 450);
DISPLAY INVISIBLE (3625 450);
FORCEPROP 2 LAST CDS_LIB pure_quanta
J 2
(3625 450);
DISPLAY INVISIBLE (3625 450);
FORCEPROP 2 LAST VOLTAGE 6.3V
J 2
(3275 500);
DISPLAY 0.553191 (3275 500);
DISPLAY INVISIBLE (3275 500);
FORCEPROP 1 LAST MATERIAL X6S
J 2
(3634 529);
DISPLAY 0.574468 (3634 529);
PAINT GREEN (3634 529);
DISPLAY INVISIBLE (3634 529);
FORCEPROP 2 LAST PACK_TYPE C0201
J 2
(3450 500);
DISPLAY 0.553191 (3450 500);
DISPLAY INVISIBLE (3450 500);
FORCEPROP 2 LAST TOLERANCE 20%
J 2
(3550 500);
DISPLAY 0.553191 (3550 500);
DISPLAY INVISIBLE (3550 500);
FORCEPROP 1 LAST PART_NUMBER SP_CH4221MEE01
J 2
(3509 538);
DISPLAY 0.574468 (3509 538);
PAINT GREEN (3509 538);
DISPLAY INVISIBLE (3509 538);
FORCEPROP 1 LAST LOCATION C770
J 0
(3875 525);
DISPLAY 1.021277 (3875 525);
DISPLAY INVISIBLE (3875 525);
FORCEPROP 1 LAST PATH I125
J 2
(3625 450);
DISPLAY 0.723404 (3625 450);
DISPLAY INVISIBLE (3625 450);
FORCEADD Q_CAP_DIFFBUS..2
R 2
(3625 600);
FORCEPROP 1 LAST LOCATION C769
J 2
(3859 617);
DISPLAY 0.723404 (3859 617);
PAINT GREEN (3859 617);
FORCEPROP 2 LAST $SEC 1
J 2
(3800 675);
DISPLAY 0.680851 (3800 675);
PAINT MONO (3800 675);
DISPLAY INVISIBLE (3800 675);
FORCEPROP 2 LAST CDS_SEC 1
J 2
(3800 675);
DISPLAY 0.680851 (3800 675);
DISPLAY INVISIBLE (3800 675);
FORCEPROP 2 LASTPIN (3700 600) $PN 1
J 0
(3710 610);
DISPLAY 0.808511 (3710 610);
FORCEPROP 2 LASTPIN (3550 600) $PN 2
J 2
(3540 610);
DISPLAY 0.808511 (3540 610);
FORCEPROP 2 LAST VALUE DIFF BUS_0.22UF
J 2
(3475 600);
DISPLAY 0.553191 (3475 600);
FORCEPROP 1 LAST PIN_NAMES_ROTATE TRUE
J 2
(3625 600);
DISPLAY 0.489362 (3625 600);
PAINT GREEN (3625 600);
DISPLAY INVISIBLE (3625 600);
FORCEPROP 2 LAST CDS_LIB pure_quanta
J 2
(3625 600);
DISPLAY INVISIBLE (3625 600);
FORCEPROP 1 LAST CDS_LMAN_SYM_OUTLINE -25,50,25,-50
J 2
(3625 600);
DISPLAY 0.468085 (3625 600);
PAINT GREEN (3625 600);
DISPLAY INVISIBLE (3625 600);
FORCEPROP 2 LAST VOLTAGE 6.3V
J 2
(3275 650);
DISPLAY 0.553191 (3275 650);
DISPLAY INVISIBLE (3275 650);
FORCEPROP 1 LAST MATERIAL X6S
J 2
(3634 679);
DISPLAY 0.574468 (3634 679);
PAINT GREEN (3634 679);
DISPLAY INVISIBLE (3634 679);
FORCEPROP 2 LAST PACK_TYPE C0201
J 2
(3450 650);
DISPLAY 0.553191 (3450 650);
DISPLAY INVISIBLE (3450 650);
FORCEPROP 2 LAST TOLERANCE 20%
J 2
(3550 650);
DISPLAY 0.553191 (3550 650);
DISPLAY INVISIBLE (3550 650);
FORCEPROP 1 LAST PART_NUMBER SP_CH4221MEE01
J 2
(3509 688);
DISPLAY 0.574468 (3509 688);
PAINT GREEN (3509 688);
DISPLAY INVISIBLE (3509 688);
FORCEPROP 1 LAST LOCATION C769
J 0
(3875 675);
DISPLAY 1.021277 (3875 675);
DISPLAY INVISIBLE (3875 675);
FORCEPROP 1 LAST PATH I126
J 2
(3625 600);
DISPLAY 0.723404 (3625 600);
DISPLAY INVISIBLE (3625 600);
FORCEADD Q_CAP_DIFFBUS..2
R 2
(3625 650);
FORCEPROP 1 LAST LOCATION C768
J 2
(3859 667);
DISPLAY 0.723404 (3859 667);
PAINT GREEN (3859 667);
FORCEPROP 2 LAST $SEC 1
J 2
(3800 725);
DISPLAY 0.680851 (3800 725);
PAINT MONO (3800 725);
DISPLAY INVISIBLE (3800 725);
FORCEPROP 2 LAST CDS_SEC 1
J 2
(3800 725);
DISPLAY 0.680851 (3800 725);
DISPLAY INVISIBLE (3800 725);
FORCEPROP 2 LASTPIN (3700 650) $PN 1
J 0
(3710 660);
DISPLAY 0.808511 (3710 660);
FORCEPROP 2 LASTPIN (3550 650) $PN 2
J 2
(3540 660);
DISPLAY 0.808511 (3540 660);
FORCEPROP 2 LAST VALUE DIFF BUS_0.22UF
J 2
(3475 650);
DISPLAY 0.553191 (3475 650);
FORCEPROP 1 LAST PIN_NAMES_ROTATE TRUE
J 2
(3625 650);
DISPLAY 0.489362 (3625 650);
PAINT GREEN (3625 650);
DISPLAY INVISIBLE (3625 650);
FORCEPROP 2 LAST CDS_LIB pure_quanta
J 2
(3625 650);
DISPLAY INVISIBLE (3625 650);
FORCEPROP 1 LAST CDS_LMAN_SYM_OUTLINE -25,50,25,-50
J 2
(3625 650);
DISPLAY 0.468085 (3625 650);
PAINT GREEN (3625 650);
DISPLAY INVISIBLE (3625 650);
FORCEPROP 2 LAST VOLTAGE 6.3V
J 2
(3275 700);
DISPLAY 0.553191 (3275 700);
DISPLAY INVISIBLE (3275 700);
FORCEPROP 1 LAST MATERIAL X6S
J 2
(3634 729);
DISPLAY 0.574468 (3634 729);
PAINT GREEN (3634 729);
DISPLAY INVISIBLE (3634 729);
FORCEPROP 2 LAST PACK_TYPE C0201
J 2
(3450 700);
DISPLAY 0.553191 (3450 700);
DISPLAY INVISIBLE (3450 700);
FORCEPROP 2 LAST TOLERANCE 20%
J 2
(3550 700);
DISPLAY 0.553191 (3550 700);
DISPLAY INVISIBLE (3550 700);
FORCEPROP 1 LAST PART_NUMBER SP_CH4221MEE01
J 2
(3509 738);
DISPLAY 0.574468 (3509 738);
PAINT GREEN (3509 738);
DISPLAY INVISIBLE (3509 738);
FORCEPROP 1 LAST LOCATION C768
J 0
(3875 725);
DISPLAY 1.021277 (3875 725);
DISPLAY INVISIBLE (3875 725);
FORCEPROP 1 LAST PATH I127
J 2
(3625 650);
DISPLAY 0.723404 (3625 650);
DISPLAY INVISIBLE (3625 650);
FORCEADD Q_CAP_DIFFBUS..2
R 2
(3625 800);
FORCEPROP 1 LAST LOCATION C767
J 2
(3859 817);
DISPLAY 0.723404 (3859 817);
PAINT GREEN (3859 817);
FORCEPROP 2 LAST $SEC 1
J 2
(3800 875);
DISPLAY 0.680851 (3800 875);
PAINT MONO (3800 875);
DISPLAY INVISIBLE (3800 875);
FORCEPROP 2 LAST CDS_SEC 1
J 2
(3800 875);
DISPLAY 0.680851 (3800 875);
DISPLAY INVISIBLE (3800 875);
FORCEPROP 2 LASTPIN (3700 800) $PN 1
J 0
(3710 810);
DISPLAY 0.808511 (3710 810);
FORCEPROP 2 LASTPIN (3550 800) $PN 2
J 2
(3540 810);
DISPLAY 0.808511 (3540 810);
FORCEPROP 2 LAST VALUE DIFF BUS_0.22UF
J 2
(3475 800);
DISPLAY 0.553191 (3475 800);
FORCEPROP 1 LAST PIN_NAMES_ROTATE TRUE
J 2
(3625 800);
DISPLAY 0.489362 (3625 800);
PAINT GREEN (3625 800);
DISPLAY INVISIBLE (3625 800);
FORCEPROP 1 LAST CDS_LMAN_SYM_OUTLINE -25,50,25,-50
J 2
(3625 800);
DISPLAY 0.468085 (3625 800);
PAINT GREEN (3625 800);
DISPLAY INVISIBLE (3625 800);
FORCEPROP 2 LAST CDS_LIB pure_quanta
J 2
(3625 800);
DISPLAY INVISIBLE (3625 800);
FORCEPROP 2 LAST VOLTAGE 6.3V
J 2
(3275 850);
DISPLAY 0.553191 (3275 850);
DISPLAY INVISIBLE (3275 850);
FORCEPROP 1 LAST MATERIAL X6S
J 2
(3634 879);
DISPLAY 0.574468 (3634 879);
PAINT GREEN (3634 879);
DISPLAY INVISIBLE (3634 879);
FORCEPROP 2 LAST PACK_TYPE C0201
J 2
(3450 850);
DISPLAY 0.553191 (3450 850);
DISPLAY INVISIBLE (3450 850);
FORCEPROP 2 LAST TOLERANCE 20%
J 2
(3550 850);
DISPLAY 0.553191 (3550 850);
DISPLAY INVISIBLE (3550 850);
FORCEPROP 1 LAST PART_NUMBER SP_CH4221MEE01
J 2
(3509 888);
DISPLAY 0.574468 (3509 888);
PAINT GREEN (3509 888);
DISPLAY INVISIBLE (3509 888);
FORCEPROP 1 LAST LOCATION C767
J 0
(3875 875);
DISPLAY 1.021277 (3875 875);
DISPLAY INVISIBLE (3875 875);
FORCEPROP 1 LAST PATH I128
J 2
(3625 800);
DISPLAY 0.723404 (3625 800);
DISPLAY INVISIBLE (3625 800);
FORCEADD Q_CAP_DIFFBUS..2
R 2
(3625 850);
FORCEPROP 1 LAST LOCATION C766
J 2
(3859 867);
DISPLAY 0.723404 (3859 867);
PAINT GREEN (3859 867);
FORCEPROP 2 LAST $SEC 1
J 2
(3800 925);
DISPLAY 0.680851 (3800 925);
PAINT MONO (3800 925);
DISPLAY INVISIBLE (3800 925);
FORCEPROP 2 LAST CDS_SEC 1
J 2
(3800 925);
DISPLAY 0.680851 (3800 925);
DISPLAY INVISIBLE (3800 925);
FORCEPROP 2 LASTPIN (3700 850) $PN 1
J 0
(3710 860);
DISPLAY 0.808511 (3710 860);
FORCEPROP 2 LASTPIN (3550 850) $PN 2
J 2
(3540 860);
DISPLAY 0.808511 (3540 860);
FORCEPROP 2 LAST VALUE DIFF BUS_0.22UF
J 2
(3475 850);
DISPLAY 0.553191 (3475 850);
FORCEPROP 1 LAST PIN_NAMES_ROTATE TRUE
J 2
(3625 850);
DISPLAY 0.489362 (3625 850);
PAINT GREEN (3625 850);
DISPLAY INVISIBLE (3625 850);
FORCEPROP 1 LAST CDS_LMAN_SYM_OUTLINE -25,50,25,-50
J 2
(3625 850);
DISPLAY 0.468085 (3625 850);
PAINT GREEN (3625 850);
DISPLAY INVISIBLE (3625 850);
FORCEPROP 2 LAST CDS_LIB pure_quanta
J 2
(3625 850);
DISPLAY INVISIBLE (3625 850);
FORCEPROP 2 LAST VOLTAGE 6.3V
J 2
(3275 900);
DISPLAY 0.553191 (3275 900);
DISPLAY INVISIBLE (3275 900);
FORCEPROP 1 LAST MATERIAL X6S
J 2
(3634 929);
DISPLAY 0.574468 (3634 929);
PAINT GREEN (3634 929);
DISPLAY INVISIBLE (3634 929);
FORCEPROP 2 LAST PACK_TYPE C0201
J 2
(3450 900);
DISPLAY 0.553191 (3450 900);
DISPLAY INVISIBLE (3450 900);
FORCEPROP 2 LAST TOLERANCE 20%
J 2
(3550 900);
DISPLAY 0.553191 (3550 900);
DISPLAY INVISIBLE (3550 900);
FORCEPROP 1 LAST PART_NUMBER SP_CH4221MEE01
J 2
(3509 938);
DISPLAY 0.574468 (3509 938);
PAINT GREEN (3509 938);
DISPLAY INVISIBLE (3509 938);
FORCEPROP 1 LAST LOCATION C766
J 0
(3875 925);
DISPLAY 1.021277 (3875 925);
DISPLAY INVISIBLE (3875 925);
FORCEPROP 1 LAST PATH I129
J 2
(3625 850);
DISPLAY 0.723404 (3625 850);
DISPLAY INVISIBLE (3625 850);
FORCEADD Q_CAP_DIFFBUS..2
R 2
(3625 1050);
FORCEPROP 1 LAST LOCATION C764
J 2
(3859 1067);
DISPLAY 0.723404 (3859 1067);
PAINT GREEN (3859 1067);
FORCEPROP 2 LAST $SEC 1
J 2
(3800 1125);
DISPLAY 0.680851 (3800 1125);
PAINT MONO (3800 1125);
DISPLAY INVISIBLE (3800 1125);
FORCEPROP 2 LAST CDS_SEC 1
J 2
(3800 1125);
DISPLAY 0.680851 (3800 1125);
DISPLAY INVISIBLE (3800 1125);
FORCEPROP 2 LASTPIN (3700 1050) $PN 1
J 0
(3710 1060);
DISPLAY 0.808511 (3710 1060);
FORCEPROP 2 LASTPIN (3550 1050) $PN 2
J 2
(3540 1060);
DISPLAY 0.808511 (3540 1060);
FORCEPROP 2 LAST VALUE DIFF BUS_0.22UF
J 2
(3475 1050);
DISPLAY 0.553191 (3475 1050);
FORCEPROP 1 LAST PIN_NAMES_ROTATE TRUE
J 2
(3625 1050);
DISPLAY 0.489362 (3625 1050);
PAINT GREEN (3625 1050);
DISPLAY INVISIBLE (3625 1050);
FORCEPROP 2 LAST CDS_LIB pure_quanta
J 2
(3625 1050);
DISPLAY INVISIBLE (3625 1050);
FORCEPROP 1 LAST CDS_LMAN_SYM_OUTLINE -25,50,25,-50
J 2
(3625 1050);
DISPLAY 0.468085 (3625 1050);
PAINT GREEN (3625 1050);
DISPLAY INVISIBLE (3625 1050);
FORCEPROP 2 LAST VOLTAGE 6.3V
J 2
(3275 1100);
DISPLAY 0.553191 (3275 1100);
DISPLAY INVISIBLE (3275 1100);
FORCEPROP 1 LAST MATERIAL X6S
J 2
(3634 1129);
DISPLAY 0.574468 (3634 1129);
PAINT GREEN (3634 1129);
DISPLAY INVISIBLE (3634 1129);
FORCEPROP 2 LAST PACK_TYPE C0201
J 2
(3450 1100);
DISPLAY 0.553191 (3450 1100);
DISPLAY INVISIBLE (3450 1100);
FORCEPROP 2 LAST TOLERANCE 20%
J 2
(3550 1100);
DISPLAY 0.553191 (3550 1100);
DISPLAY INVISIBLE (3550 1100);
FORCEPROP 1 LAST PART_NUMBER SP_CH4221MEE01
J 2
(3509 1138);
DISPLAY 0.574468 (3509 1138);
PAINT GREEN (3509 1138);
DISPLAY INVISIBLE (3509 1138);
FORCEPROP 1 LAST LOCATION C764
J 0
(3875 1125);
DISPLAY 1.021277 (3875 1125);
DISPLAY INVISIBLE (3875 1125);
FORCEPROP 1 LAST PATH I130
J 2
(3625 1050);
DISPLAY 0.723404 (3625 1050);
DISPLAY INVISIBLE (3625 1050);
FORCEADD Q_CAP_DIFFBUS..2
R 2
(3625 1000);
FORCEPROP 1 LAST LOCATION C765
J 2
(3859 1017);
DISPLAY 0.723404 (3859 1017);
PAINT GREEN (3859 1017);
FORCEPROP 2 LAST $SEC 1
J 2
(3800 1075);
DISPLAY 0.680851 (3800 1075);
PAINT MONO (3800 1075);
DISPLAY INVISIBLE (3800 1075);
FORCEPROP 2 LAST CDS_SEC 1
J 2
(3800 1075);
DISPLAY 0.680851 (3800 1075);
DISPLAY INVISIBLE (3800 1075);
FORCEPROP 2 LASTPIN (3700 1000) $PN 1
J 0
(3710 1010);
DISPLAY 0.808511 (3710 1010);
FORCEPROP 2 LASTPIN (3550 1000) $PN 2
J 2
(3540 1010);
DISPLAY 0.808511 (3540 1010);
FORCEPROP 2 LAST VALUE DIFF BUS_0.22UF
J 2
(3475 1000);
DISPLAY 0.553191 (3475 1000);
FORCEPROP 1 LAST PIN_NAMES_ROTATE TRUE
J 2
(3625 1000);
DISPLAY 0.489362 (3625 1000);
PAINT GREEN (3625 1000);
DISPLAY INVISIBLE (3625 1000);
FORCEPROP 2 LAST CDS_LIB pure_quanta
J 2
(3625 1000);
DISPLAY INVISIBLE (3625 1000);
FORCEPROP 1 LAST CDS_LMAN_SYM_OUTLINE -25,50,25,-50
J 2
(3625 1000);
DISPLAY 0.468085 (3625 1000);
PAINT GREEN (3625 1000);
DISPLAY INVISIBLE (3625 1000);
FORCEPROP 2 LAST VOLTAGE 6.3V
J 2
(3275 1050);
DISPLAY 0.553191 (3275 1050);
DISPLAY INVISIBLE (3275 1050);
FORCEPROP 1 LAST MATERIAL X6S
J 2
(3634 1079);
DISPLAY 0.574468 (3634 1079);
PAINT GREEN (3634 1079);
DISPLAY INVISIBLE (3634 1079);
FORCEPROP 2 LAST PACK_TYPE C0201
J 2
(3450 1050);
DISPLAY 0.553191 (3450 1050);
DISPLAY INVISIBLE (3450 1050);
FORCEPROP 2 LAST TOLERANCE 20%
J 2
(3550 1050);
DISPLAY 0.553191 (3550 1050);
DISPLAY INVISIBLE (3550 1050);
FORCEPROP 1 LAST PART_NUMBER SP_CH4221MEE01
J 2
(3509 1088);
DISPLAY 0.574468 (3509 1088);
PAINT GREEN (3509 1088);
DISPLAY INVISIBLE (3509 1088);
FORCEPROP 1 LAST LOCATION C765
J 0
(3875 1075);
DISPLAY 1.021277 (3875 1075);
DISPLAY INVISIBLE (3875 1075);
FORCEPROP 1 LAST PATH I131
J 2
(3625 1000);
DISPLAY 0.723404 (3625 1000);
DISPLAY INVISIBLE (3625 1000);
FORCEADD TAP..1
R 2
(2900 1250);
FORCEPROP 3 LASTPIN (2950 1250) SIG_NAME P5E_CPU1_P2_TX_DN<5>
J 0
(2960 1260);
DISPLAY 0.659574 (2960 1260);
PAINT MONO (2960 1260);
DISPLAY INVISIBLE (2960 1260);
FORCEPROP 1 LASTPIN (2950 1250) BN 5
J 2
(2962 1258);
DISPLAY 0.680851 (2962 1258);
PAINT GREEN (2962 1258);
FORCEPROP 2 LAST CDS_LIB standard
J 0
(2900 1250);
DISPLAY INVISIBLE (2900 1250);
FORCEPROP 1 LAST BODY_TYPE PLUMBING
J 2
(2900 1300);
DISPLAY 0.872340 (2900 1300);
PAINT GREEN (2900 1300);
DISPLAY INVISIBLE (2900 1300);
FORCEPROP 1 LAST HDL_TAP TRUE
J 2
(2575 1125);
DISPLAY 0.872340 (2575 1125);
DISPLAY INVISIBLE (2575 1125);
FORCEPROP 1 LAST PATH I132
J 2
(2902 1250);
DISPLAY 0.872340 (2902 1250);
PAINT GREEN (2902 1250);
DISPLAY INVISIBLE (2902 1250);
FORCEADD TAP..1
R 2
(2900 1450);
FORCEPROP 3 LASTPIN (2950 1450) SIG_NAME P5E_CPU1_P2_TX_DN<6>
J 0
(2960 1460);
DISPLAY 0.659574 (2960 1460);
PAINT MONO (2960 1460);
DISPLAY INVISIBLE (2960 1460);
FORCEPROP 1 LASTPIN (2950 1450) BN 6
J 2
(2962 1458);
DISPLAY 0.680851 (2962 1458);
PAINT GREEN (2962 1458);
FORCEPROP 2 LAST CDS_LIB standard
J 0
(2900 1450);
DISPLAY INVISIBLE (2900 1450);
FORCEPROP 1 LAST BODY_TYPE PLUMBING
J 2
(2900 1500);
DISPLAY 0.872340 (2900 1500);
PAINT GREEN (2900 1500);
DISPLAY INVISIBLE (2900 1500);
FORCEPROP 1 LAST HDL_TAP TRUE
J 2
(2575 1325);
DISPLAY 0.872340 (2575 1325);
DISPLAY INVISIBLE (2575 1325);
FORCEPROP 1 LAST PATH I133
J 2
(2902 1450);
DISPLAY 0.872340 (2902 1450);
PAINT GREEN (2902 1450);
DISPLAY INVISIBLE (2902 1450);
FORCEADD TAP..1
R 2
(2900 1650);
FORCEPROP 3 LASTPIN (2950 1650) SIG_NAME P5E_CPU1_P2_TX_DN<7>
J 0
(2960 1660);
DISPLAY 0.659574 (2960 1660);
PAINT MONO (2960 1660);
DISPLAY INVISIBLE (2960 1660);
FORCEPROP 1 LASTPIN (2950 1650) BN 7
J 2
(2962 1658);
DISPLAY 0.680851 (2962 1658);
PAINT GREEN (2962 1658);
FORCEPROP 2 LAST CDS_LIB standard
J 0
(2900 1650);
DISPLAY INVISIBLE (2900 1650);
FORCEPROP 1 LAST BODY_TYPE PLUMBING
J 2
(2900 1700);
DISPLAY 0.872340 (2900 1700);
PAINT GREEN (2900 1700);
DISPLAY INVISIBLE (2900 1700);
FORCEPROP 1 LAST HDL_TAP TRUE
J 2
(2575 1525);
DISPLAY 0.872340 (2575 1525);
DISPLAY INVISIBLE (2575 1525);
FORCEPROP 1 LAST PATH I134
J 2
(2902 1650);
DISPLAY 0.872340 (2902 1650);
PAINT GREEN (2902 1650);
DISPLAY INVISIBLE (2902 1650);
FORCEADD Q_CAP_DIFFBUS..2
R 2
(3625 1200);
FORCEPROP 1 LAST LOCATION C763
J 2
(3859 1217);
DISPLAY 0.723404 (3859 1217);
PAINT GREEN (3859 1217);
FORCEPROP 2 LAST $SEC 1
J 2
(3800 1275);
DISPLAY 0.680851 (3800 1275);
PAINT MONO (3800 1275);
DISPLAY INVISIBLE (3800 1275);
FORCEPROP 2 LAST CDS_SEC 1
J 2
(3800 1275);
DISPLAY 0.680851 (3800 1275);
DISPLAY INVISIBLE (3800 1275);
FORCEPROP 2 LASTPIN (3700 1200) $PN 1
J 0
(3710 1210);
DISPLAY 0.808511 (3710 1210);
FORCEPROP 2 LASTPIN (3550 1200) $PN 2
J 2
(3540 1210);
DISPLAY 0.808511 (3540 1210);
FORCEPROP 2 LAST VALUE DIFF BUS_0.22UF
J 2
(3475 1200);
DISPLAY 0.553191 (3475 1200);
FORCEPROP 1 LAST PIN_NAMES_ROTATE TRUE
J 2
(3625 1200);
DISPLAY 0.489362 (3625 1200);
PAINT GREEN (3625 1200);
DISPLAY INVISIBLE (3625 1200);
FORCEPROP 2 LAST CDS_LIB pure_quanta
J 2
(3625 1200);
DISPLAY INVISIBLE (3625 1200);
FORCEPROP 1 LAST CDS_LMAN_SYM_OUTLINE -25,50,25,-50
J 2
(3625 1200);
DISPLAY 0.468085 (3625 1200);
PAINT GREEN (3625 1200);
DISPLAY INVISIBLE (3625 1200);
FORCEPROP 2 LAST VOLTAGE 6.3V
J 2
(3275 1250);
DISPLAY 0.553191 (3275 1250);
DISPLAY INVISIBLE (3275 1250);
FORCEPROP 1 LAST MATERIAL X6S
J 2
(3634 1279);
DISPLAY 0.574468 (3634 1279);
PAINT GREEN (3634 1279);
DISPLAY INVISIBLE (3634 1279);
FORCEPROP 2 LAST PACK_TYPE C0201
J 2
(3450 1250);
DISPLAY 0.553191 (3450 1250);
DISPLAY INVISIBLE (3450 1250);
FORCEPROP 2 LAST TOLERANCE 20%
J 2
(3550 1250);
DISPLAY 0.553191 (3550 1250);
DISPLAY INVISIBLE (3550 1250);
FORCEPROP 1 LAST PART_NUMBER SP_CH4221MEE01
J 2
(3509 1288);
DISPLAY 0.574468 (3509 1288);
PAINT GREEN (3509 1288);
DISPLAY INVISIBLE (3509 1288);
FORCEPROP 1 LAST LOCATION C763
J 0
(3875 1275);
DISPLAY 1.021277 (3875 1275);
DISPLAY INVISIBLE (3875 1275);
FORCEPROP 1 LAST PATH I135
J 2
(3625 1200);
DISPLAY 0.723404 (3625 1200);
DISPLAY INVISIBLE (3625 1200);
FORCEADD Q_CAP_DIFFBUS..2
R 2
(3625 1250);
FORCEPROP 1 LAST LOCATION C762
J 2
(3859 1267);
DISPLAY 0.723404 (3859 1267);
PAINT GREEN (3859 1267);
FORCEPROP 2 LAST $SEC 1
J 2
(3800 1325);
DISPLAY 0.680851 (3800 1325);
PAINT MONO (3800 1325);
DISPLAY INVISIBLE (3800 1325);
FORCEPROP 2 LAST CDS_SEC 1
J 2
(3800 1325);
DISPLAY 0.680851 (3800 1325);
DISPLAY INVISIBLE (3800 1325);
FORCEPROP 2 LASTPIN (3700 1250) $PN 1
J 0
(3710 1260);
DISPLAY 0.808511 (3710 1260);
FORCEPROP 2 LASTPIN (3550 1250) $PN 2
J 2
(3540 1260);
DISPLAY 0.808511 (3540 1260);
FORCEPROP 2 LAST VALUE DIFF BUS_0.22UF
J 2
(3475 1250);
DISPLAY 0.553191 (3475 1250);
FORCEPROP 1 LAST PIN_NAMES_ROTATE TRUE
J 2
(3625 1250);
DISPLAY 0.489362 (3625 1250);
PAINT GREEN (3625 1250);
DISPLAY INVISIBLE (3625 1250);
FORCEPROP 2 LAST CDS_LIB pure_quanta
J 2
(3625 1250);
DISPLAY INVISIBLE (3625 1250);
FORCEPROP 1 LAST CDS_LMAN_SYM_OUTLINE -25,50,25,-50
J 2
(3625 1250);
DISPLAY 0.468085 (3625 1250);
PAINT GREEN (3625 1250);
DISPLAY INVISIBLE (3625 1250);
FORCEPROP 2 LAST VOLTAGE 6.3V
J 2
(3275 1300);
DISPLAY 0.553191 (3275 1300);
DISPLAY INVISIBLE (3275 1300);
FORCEPROP 1 LAST MATERIAL X6S
J 2
(3634 1329);
DISPLAY 0.574468 (3634 1329);
PAINT GREEN (3634 1329);
DISPLAY INVISIBLE (3634 1329);
FORCEPROP 2 LAST PACK_TYPE C0201
J 2
(3450 1300);
DISPLAY 0.553191 (3450 1300);
DISPLAY INVISIBLE (3450 1300);
FORCEPROP 2 LAST TOLERANCE 20%
J 2
(3550 1300);
DISPLAY 0.553191 (3550 1300);
DISPLAY INVISIBLE (3550 1300);
FORCEPROP 1 LAST PART_NUMBER SP_CH4221MEE01
J 2
(3509 1338);
DISPLAY 0.574468 (3509 1338);
PAINT GREEN (3509 1338);
DISPLAY INVISIBLE (3509 1338);
FORCEPROP 1 LAST LOCATION C762
J 0
(3875 1325);
DISPLAY 1.021277 (3875 1325);
DISPLAY INVISIBLE (3875 1325);
FORCEPROP 1 LAST PATH I136
J 2
(3625 1250);
DISPLAY 0.723404 (3625 1250);
DISPLAY INVISIBLE (3625 1250);
FORCEADD Q_CAP_DIFFBUS..2
R 2
(3625 1400);
FORCEPROP 1 LAST LOCATION C761
J 2
(3859 1417);
DISPLAY 0.723404 (3859 1417);
PAINT GREEN (3859 1417);
FORCEPROP 2 LAST $SEC 1
J 2
(3800 1475);
DISPLAY 0.680851 (3800 1475);
PAINT MONO (3800 1475);
DISPLAY INVISIBLE (3800 1475);
FORCEPROP 2 LAST CDS_SEC 1
J 2
(3800 1475);
DISPLAY 0.680851 (3800 1475);
DISPLAY INVISIBLE (3800 1475);
FORCEPROP 2 LASTPIN (3700 1400) $PN 1
J 0
(3710 1410);
DISPLAY 0.808511 (3710 1410);
FORCEPROP 2 LASTPIN (3550 1400) $PN 2
J 2
(3540 1410);
DISPLAY 0.808511 (3540 1410);
FORCEPROP 2 LAST VALUE DIFF BUS_0.22UF
J 2
(3475 1400);
DISPLAY 0.553191 (3475 1400);
FORCEPROP 1 LAST PIN_NAMES_ROTATE TRUE
J 2
(3625 1400);
DISPLAY 0.489362 (3625 1400);
PAINT GREEN (3625 1400);
DISPLAY INVISIBLE (3625 1400);
FORCEPROP 2 LAST CDS_LIB pure_quanta
J 2
(3625 1400);
DISPLAY INVISIBLE (3625 1400);
FORCEPROP 1 LAST CDS_LMAN_SYM_OUTLINE -25,50,25,-50
J 2
(3625 1400);
DISPLAY 0.468085 (3625 1400);
PAINT GREEN (3625 1400);
DISPLAY INVISIBLE (3625 1400);
FORCEPROP 2 LAST VOLTAGE 6.3V
J 2
(3275 1450);
DISPLAY 0.553191 (3275 1450);
DISPLAY INVISIBLE (3275 1450);
FORCEPROP 1 LAST MATERIAL X6S
J 2
(3634 1479);
DISPLAY 0.574468 (3634 1479);
PAINT GREEN (3634 1479);
DISPLAY INVISIBLE (3634 1479);
FORCEPROP 2 LAST PACK_TYPE C0201
J 2
(3450 1450);
DISPLAY 0.553191 (3450 1450);
DISPLAY INVISIBLE (3450 1450);
FORCEPROP 2 LAST TOLERANCE 20%
J 2
(3550 1450);
DISPLAY 0.553191 (3550 1450);
DISPLAY INVISIBLE (3550 1450);
FORCEPROP 1 LAST PART_NUMBER SP_CH4221MEE01
J 2
(3509 1488);
DISPLAY 0.574468 (3509 1488);
PAINT GREEN (3509 1488);
DISPLAY INVISIBLE (3509 1488);
FORCEPROP 1 LAST LOCATION C761
J 0
(3875 1475);
DISPLAY 1.021277 (3875 1475);
DISPLAY INVISIBLE (3875 1475);
FORCEPROP 1 LAST PATH I137
J 2
(3625 1400);
DISPLAY 0.723404 (3625 1400);
DISPLAY INVISIBLE (3625 1400);
FORCEADD Q_CAP_DIFFBUS..2
R 2
(3625 1450);
FORCEPROP 1 LAST LOCATION C760
J 2
(3859 1467);
DISPLAY 0.723404 (3859 1467);
PAINT GREEN (3859 1467);
FORCEPROP 2 LAST $SEC 1
J 2
(3800 1525);
DISPLAY 0.680851 (3800 1525);
PAINT MONO (3800 1525);
DISPLAY INVISIBLE (3800 1525);
FORCEPROP 2 LAST CDS_SEC 1
J 2
(3800 1525);
DISPLAY 0.680851 (3800 1525);
DISPLAY INVISIBLE (3800 1525);
FORCEPROP 2 LASTPIN (3700 1450) $PN 1
J 0
(3710 1460);
DISPLAY 0.808511 (3710 1460);
FORCEPROP 2 LASTPIN (3550 1450) $PN 2
J 2
(3540 1460);
DISPLAY 0.808511 (3540 1460);
FORCEPROP 2 LAST VALUE DIFF BUS_0.22UF
J 2
(3475 1450);
DISPLAY 0.553191 (3475 1450);
FORCEPROP 1 LAST PIN_NAMES_ROTATE TRUE
J 2
(3625 1450);
DISPLAY 0.489362 (3625 1450);
PAINT GREEN (3625 1450);
DISPLAY INVISIBLE (3625 1450);
FORCEPROP 2 LAST CDS_LIB pure_quanta
J 2
(3625 1450);
DISPLAY INVISIBLE (3625 1450);
FORCEPROP 1 LAST CDS_LMAN_SYM_OUTLINE -25,50,25,-50
J 2
(3625 1450);
DISPLAY 0.468085 (3625 1450);
PAINT GREEN (3625 1450);
DISPLAY INVISIBLE (3625 1450);
FORCEPROP 2 LAST VOLTAGE 6.3V
J 2
(3275 1500);
DISPLAY 0.553191 (3275 1500);
DISPLAY INVISIBLE (3275 1500);
FORCEPROP 1 LAST MATERIAL X6S
J 2
(3634 1529);
DISPLAY 0.574468 (3634 1529);
PAINT GREEN (3634 1529);
DISPLAY INVISIBLE (3634 1529);
FORCEPROP 2 LAST PACK_TYPE C0201
J 2
(3450 1500);
DISPLAY 0.553191 (3450 1500);
DISPLAY INVISIBLE (3450 1500);
FORCEPROP 2 LAST TOLERANCE 20%
J 2
(3550 1500);
DISPLAY 0.553191 (3550 1500);
DISPLAY INVISIBLE (3550 1500);
FORCEPROP 1 LAST PART_NUMBER SP_CH4221MEE01
J 2
(3509 1538);
DISPLAY 0.574468 (3509 1538);
PAINT GREEN (3509 1538);
DISPLAY INVISIBLE (3509 1538);
FORCEPROP 1 LAST LOCATION C760
J 0
(3875 1525);
DISPLAY 1.021277 (3875 1525);
DISPLAY INVISIBLE (3875 1525);
FORCEPROP 1 LAST PATH I138
J 2
(3625 1450);
DISPLAY 0.723404 (3625 1450);
DISPLAY INVISIBLE (3625 1450);
FORCEADD Q_CAP_DIFFBUS..2
R 2
(3625 1600);
FORCEPROP 1 LAST LOCATION C759
J 2
(3859 1617);
DISPLAY 0.723404 (3859 1617);
PAINT GREEN (3859 1617);
FORCEPROP 2 LAST $SEC 1
J 2
(3800 1675);
DISPLAY 0.680851 (3800 1675);
PAINT MONO (3800 1675);
DISPLAY INVISIBLE (3800 1675);
FORCEPROP 2 LAST CDS_SEC 1
J 2
(3800 1675);
DISPLAY 0.680851 (3800 1675);
DISPLAY INVISIBLE (3800 1675);
FORCEPROP 2 LASTPIN (3700 1600) $PN 1
J 0
(3710 1610);
DISPLAY 0.808511 (3710 1610);
FORCEPROP 2 LASTPIN (3550 1600) $PN 2
J 2
(3540 1610);
DISPLAY 0.808511 (3540 1610);
FORCEPROP 2 LAST VALUE DIFF BUS_0.22UF
J 2
(3475 1600);
DISPLAY 0.553191 (3475 1600);
FORCEPROP 1 LAST PIN_NAMES_ROTATE TRUE
J 2
(3625 1600);
DISPLAY 0.489362 (3625 1600);
PAINT GREEN (3625 1600);
DISPLAY INVISIBLE (3625 1600);
FORCEPROP 2 LAST CDS_LIB pure_quanta
J 2
(3625 1600);
DISPLAY INVISIBLE (3625 1600);
FORCEPROP 1 LAST CDS_LMAN_SYM_OUTLINE -25,50,25,-50
J 2
(3625 1600);
DISPLAY 0.468085 (3625 1600);
PAINT GREEN (3625 1600);
DISPLAY INVISIBLE (3625 1600);
FORCEPROP 2 LAST VOLTAGE 6.3V
J 2
(3275 1650);
DISPLAY 0.553191 (3275 1650);
DISPLAY INVISIBLE (3275 1650);
FORCEPROP 1 LAST MATERIAL X6S
J 2
(3634 1679);
DISPLAY 0.574468 (3634 1679);
PAINT GREEN (3634 1679);
DISPLAY INVISIBLE (3634 1679);
FORCEPROP 2 LAST PACK_TYPE C0201
J 2
(3450 1650);
DISPLAY 0.553191 (3450 1650);
DISPLAY INVISIBLE (3450 1650);
FORCEPROP 2 LAST TOLERANCE 20%
J 2
(3550 1650);
DISPLAY 0.553191 (3550 1650);
DISPLAY INVISIBLE (3550 1650);
FORCEPROP 1 LAST PART_NUMBER SP_CH4221MEE01
J 2
(3509 1688);
DISPLAY 0.574468 (3509 1688);
PAINT GREEN (3509 1688);
DISPLAY INVISIBLE (3509 1688);
FORCEPROP 1 LAST LOCATION C759
J 0
(3875 1675);
DISPLAY 1.021277 (3875 1675);
DISPLAY INVISIBLE (3875 1675);
FORCEPROP 1 LAST PATH I139
J 2
(3625 1600);
DISPLAY 0.723404 (3625 1600);
DISPLAY INVISIBLE (3625 1600);
FORCEADD Q_CAP_DIFFBUS..2
R 2
(3625 1650);
FORCEPROP 1 LAST LOCATION C758
J 2
(3859 1667);
DISPLAY 0.723404 (3859 1667);
PAINT GREEN (3859 1667);
FORCEPROP 2 LAST $SEC 1
J 2
(3800 1725);
DISPLAY 0.680851 (3800 1725);
PAINT MONO (3800 1725);
DISPLAY INVISIBLE (3800 1725);
FORCEPROP 2 LAST CDS_SEC 1
J 2
(3800 1725);
DISPLAY 0.680851 (3800 1725);
DISPLAY INVISIBLE (3800 1725);
FORCEPROP 2 LASTPIN (3700 1650) $PN 1
J 0
(3710 1660);
DISPLAY 0.808511 (3710 1660);
FORCEPROP 2 LASTPIN (3550 1650) $PN 2
J 2
(3540 1660);
DISPLAY 0.808511 (3540 1660);
FORCEPROP 2 LAST VALUE DIFF BUS_0.22UF
J 2
(3475 1650);
DISPLAY 0.553191 (3475 1650);
FORCEPROP 1 LAST PIN_NAMES_ROTATE TRUE
J 2
(3625 1650);
DISPLAY 0.489362 (3625 1650);
PAINT GREEN (3625 1650);
DISPLAY INVISIBLE (3625 1650);
FORCEPROP 1 LAST CDS_LMAN_SYM_OUTLINE -25,50,25,-50
J 2
(3625 1650);
DISPLAY 0.468085 (3625 1650);
PAINT GREEN (3625 1650);
DISPLAY INVISIBLE (3625 1650);
FORCEPROP 2 LAST CDS_LIB pure_quanta
J 2
(3625 1650);
DISPLAY INVISIBLE (3625 1650);
FORCEPROP 2 LAST VOLTAGE 6.3V
J 2
(3275 1700);
DISPLAY 0.553191 (3275 1700);
DISPLAY INVISIBLE (3275 1700);
FORCEPROP 1 LAST MATERIAL X6S
J 2
(3634 1729);
DISPLAY 0.574468 (3634 1729);
PAINT GREEN (3634 1729);
DISPLAY INVISIBLE (3634 1729);
FORCEPROP 2 LAST PACK_TYPE C0201
J 2
(3450 1700);
DISPLAY 0.553191 (3450 1700);
DISPLAY INVISIBLE (3450 1700);
FORCEPROP 2 LAST TOLERANCE 20%
J 2
(3550 1700);
DISPLAY 0.553191 (3550 1700);
DISPLAY INVISIBLE (3550 1700);
FORCEPROP 1 LAST PART_NUMBER SP_CH4221MEE01
J 2
(3509 1738);
DISPLAY 0.574468 (3509 1738);
PAINT GREEN (3509 1738);
DISPLAY INVISIBLE (3509 1738);
FORCEPROP 1 LAST LOCATION C758
J 0
(3875 1725);
DISPLAY 1.021277 (3875 1725);
DISPLAY INVISIBLE (3875 1725);
FORCEPROP 1 LAST PATH I140
J 2
(3625 1650);
DISPLAY 0.723404 (3625 1650);
DISPLAY INVISIBLE (3625 1650);
FORCEADD TAP..1
R 2
(2650 2175);
FORCEPROP 3 LASTPIN (2700 2175) SIG_NAME P5E_CPU1_P2_TX_DP<8>
J 0
(2710 2185);
DISPLAY 0.659574 (2710 2185);
PAINT MONO (2710 2185);
DISPLAY INVISIBLE (2710 2185);
FORCEPROP 1 LASTPIN (2700 2175) BN 8
J 2
(2712 2183);
DISPLAY 0.680851 (2712 2183);
PAINT GREEN (2712 2183);
FORCEPROP 2 LAST CDS_LIB standard
J 0
(2650 2175);
DISPLAY INVISIBLE (2650 2175);
FORCEPROP 1 LAST BODY_TYPE PLUMBING
J 2
(2650 2225);
DISPLAY 0.872340 (2650 2225);
PAINT GREEN (2650 2225);
DISPLAY INVISIBLE (2650 2225);
FORCEPROP 1 LAST HDL_TAP TRUE
J 2
(2325 2050);
DISPLAY 0.872340 (2325 2050);
DISPLAY INVISIBLE (2325 2050);
FORCEPROP 1 LAST PATH I141
J 2
(2652 2175);
DISPLAY 0.872340 (2652 2175);
PAINT GREEN (2652 2175);
DISPLAY INVISIBLE (2652 2175);
FORCEADD TAP..1
R 2
(2650 2375);
FORCEPROP 3 LASTPIN (2700 2375) SIG_NAME P5E_CPU1_P2_TX_DP<9>
J 0
(2710 2385);
DISPLAY 0.659574 (2710 2385);
PAINT MONO (2710 2385);
DISPLAY INVISIBLE (2710 2385);
FORCEPROP 1 LASTPIN (2700 2375) BN 9
J 2
(2712 2383);
DISPLAY 0.680851 (2712 2383);
PAINT GREEN (2712 2383);
FORCEPROP 2 LAST CDS_LIB standard
J 0
(2650 2375);
DISPLAY INVISIBLE (2650 2375);
FORCEPROP 1 LAST BODY_TYPE PLUMBING
J 2
(2650 2425);
DISPLAY 0.872340 (2650 2425);
PAINT GREEN (2650 2425);
DISPLAY INVISIBLE (2650 2425);
FORCEPROP 1 LAST HDL_TAP TRUE
J 2
(2325 2250);
DISPLAY 0.872340 (2325 2250);
DISPLAY INVISIBLE (2325 2250);
FORCEPROP 1 LAST PATH I142
J 2
(2652 2375);
DISPLAY 0.872340 (2652 2375);
PAINT GREEN (2652 2375);
DISPLAY INVISIBLE (2652 2375);
FORCEADD TAP..1
R 2
(2650 2575);
FORCEPROP 3 LASTPIN (2700 2575) SIG_NAME P5E_CPU1_P2_TX_DP<10>
J 0
(2710 2585);
DISPLAY 0.659574 (2710 2585);
PAINT MONO (2710 2585);
DISPLAY INVISIBLE (2710 2585);
FORCEPROP 1 LASTPIN (2700 2575) BN 10
J 2
(2712 2583);
DISPLAY 0.680851 (2712 2583);
PAINT GREEN (2712 2583);
FORCEPROP 2 LAST CDS_LIB standard
J 0
(2650 2575);
DISPLAY INVISIBLE (2650 2575);
FORCEPROP 1 LAST BODY_TYPE PLUMBING
J 2
(2650 2625);
DISPLAY 0.872340 (2650 2625);
PAINT GREEN (2650 2625);
DISPLAY INVISIBLE (2650 2625);
FORCEPROP 1 LAST HDL_TAP TRUE
J 2
(2325 2450);
DISPLAY 0.872340 (2325 2450);
DISPLAY INVISIBLE (2325 2450);
FORCEPROP 1 LAST PATH I143
J 2
(2652 2575);
DISPLAY 0.872340 (2652 2575);
PAINT GREEN (2652 2575);
DISPLAY INVISIBLE (2652 2575);
FORCEADD TAP..1
R 2
(2650 2775);
FORCEPROP 3 LASTPIN (2700 2775) SIG_NAME P5E_CPU1_P2_TX_DP<11>
J 0
(2710 2785);
DISPLAY 0.659574 (2710 2785);
PAINT MONO (2710 2785);
DISPLAY INVISIBLE (2710 2785);
FORCEPROP 1 LASTPIN (2700 2775) BN 11
J 2
(2712 2783);
DISPLAY 0.680851 (2712 2783);
PAINT GREEN (2712 2783);
FORCEPROP 2 LAST CDS_LIB standard
J 0
(2650 2775);
DISPLAY INVISIBLE (2650 2775);
FORCEPROP 1 LAST BODY_TYPE PLUMBING
J 2
(2650 2825);
DISPLAY 0.872340 (2650 2825);
PAINT GREEN (2650 2825);
DISPLAY INVISIBLE (2650 2825);
FORCEPROP 1 LAST HDL_TAP TRUE
J 2
(2325 2650);
DISPLAY 0.872340 (2325 2650);
DISPLAY INVISIBLE (2325 2650);
FORCEPROP 1 LAST PATH I144
J 2
(2652 2775);
DISPLAY 0.872340 (2652 2775);
PAINT GREEN (2652 2775);
DISPLAY INVISIBLE (2652 2775);
FORCEADD TAP..1
R 2
(2650 2975);
FORCEPROP 3 LASTPIN (2700 2975) SIG_NAME P5E_CPU1_P2_TX_DP<12>
J 0
(2710 2985);
DISPLAY 0.659574 (2710 2985);
PAINT MONO (2710 2985);
DISPLAY INVISIBLE (2710 2985);
FORCEPROP 1 LASTPIN (2700 2975) BN 12
J 2
(2712 2983);
DISPLAY 0.680851 (2712 2983);
PAINT GREEN (2712 2983);
FORCEPROP 2 LAST CDS_LIB standard
J 0
(2650 2975);
DISPLAY INVISIBLE (2650 2975);
FORCEPROP 1 LAST BODY_TYPE PLUMBING
J 2
(2650 3025);
DISPLAY 0.872340 (2650 3025);
PAINT GREEN (2650 3025);
DISPLAY INVISIBLE (2650 3025);
FORCEPROP 1 LAST HDL_TAP TRUE
J 2
(2325 2850);
DISPLAY 0.872340 (2325 2850);
DISPLAY INVISIBLE (2325 2850);
FORCEPROP 1 LAST PATH I145
J 2
(2652 2975);
DISPLAY 0.872340 (2652 2975);
PAINT GREEN (2652 2975);
DISPLAY INVISIBLE (2652 2975);
FORCEADD TAP..1
R 2
(2650 3175);
FORCEPROP 3 LASTPIN (2700 3175) SIG_NAME P5E_CPU1_P2_TX_DP<13>
J 0
(2710 3185);
DISPLAY 0.659574 (2710 3185);
PAINT MONO (2710 3185);
DISPLAY INVISIBLE (2710 3185);
FORCEPROP 1 LASTPIN (2700 3175) BN 13
J 2
(2712 3183);
DISPLAY 0.680851 (2712 3183);
PAINT GREEN (2712 3183);
FORCEPROP 2 LAST CDS_LIB standard
J 0
(2650 3175);
DISPLAY INVISIBLE (2650 3175);
FORCEPROP 1 LAST BODY_TYPE PLUMBING
J 2
(2650 3225);
DISPLAY 0.872340 (2650 3225);
PAINT GREEN (2650 3225);
DISPLAY INVISIBLE (2650 3225);
FORCEPROP 1 LAST HDL_TAP TRUE
J 2
(2325 3050);
DISPLAY 0.872340 (2325 3050);
DISPLAY INVISIBLE (2325 3050);
FORCEPROP 1 LAST PATH I146
J 2
(2652 3175);
DISPLAY 0.872340 (2652 3175);
PAINT GREEN (2652 3175);
DISPLAY INVISIBLE (2652 3175);
FORCEADD TAP..1
R 2
(2650 3375);
FORCEPROP 3 LASTPIN (2700 3375) SIG_NAME P5E_CPU1_P2_TX_DP<14>
J 0
(2710 3385);
DISPLAY 0.659574 (2710 3385);
PAINT MONO (2710 3385);
DISPLAY INVISIBLE (2710 3385);
FORCEPROP 1 LASTPIN (2700 3375) BN 14
J 2
(2712 3383);
DISPLAY 0.680851 (2712 3383);
PAINT GREEN (2712 3383);
FORCEPROP 2 LAST CDS_LIB standard
J 0
(2650 3375);
DISPLAY INVISIBLE (2650 3375);
FORCEPROP 1 LAST BODY_TYPE PLUMBING
J 2
(2650 3425);
DISPLAY 0.872340 (2650 3425);
PAINT GREEN (2650 3425);
DISPLAY INVISIBLE (2650 3425);
FORCEPROP 1 LAST HDL_TAP TRUE
J 2
(2325 3250);
DISPLAY 0.872340 (2325 3250);
DISPLAY INVISIBLE (2325 3250);
FORCEPROP 1 LAST PATH I147
J 2
(2652 3375);
DISPLAY 0.872340 (2652 3375);
PAINT GREEN (2652 3375);
DISPLAY INVISIBLE (2652 3375);
FORCEADD TAP..1
R 2
(2650 3575);
FORCEPROP 3 LASTPIN (2700 3575) SIG_NAME P5E_CPU1_P2_TX_DP<15>
J 0
(2710 3585);
DISPLAY 0.659574 (2710 3585);
PAINT MONO (2710 3585);
DISPLAY INVISIBLE (2710 3585);
FORCEPROP 1 LASTPIN (2700 3575) BN 15
J 2
(2712 3583);
DISPLAY 0.680851 (2712 3583);
PAINT GREEN (2712 3583);
FORCEPROP 2 LAST CDS_LIB standard
J 0
(2650 3575);
DISPLAY INVISIBLE (2650 3575);
FORCEPROP 1 LAST BODY_TYPE PLUMBING
J 2
(2650 3625);
DISPLAY 0.872340 (2650 3625);
PAINT GREEN (2650 3625);
DISPLAY INVISIBLE (2650 3625);
FORCEPROP 1 LAST HDL_TAP TRUE
J 2
(2325 3450);
DISPLAY 0.872340 (2325 3450);
DISPLAY INVISIBLE (2325 3450);
FORCEPROP 1 LAST PATH I148
J 2
(2652 3575);
DISPLAY 0.872340 (2652 3575);
PAINT GREEN (2652 3575);
DISPLAY INVISIBLE (2652 3575);
FORCEADD TAP..1
R 2
(2900 2225);
FORCEPROP 3 LASTPIN (2950 2225) SIG_NAME P5E_CPU1_P2_TX_DN<8>
J 0
(2960 2235);
DISPLAY 0.659574 (2960 2235);
PAINT MONO (2960 2235);
DISPLAY INVISIBLE (2960 2235);
FORCEPROP 1 LASTPIN (2950 2225) BN 8
J 2
(2962 2233);
DISPLAY 0.680851 (2962 2233);
PAINT GREEN (2962 2233);
FORCEPROP 2 LAST CDS_LIB standard
J 0
(2900 2225);
DISPLAY INVISIBLE (2900 2225);
FORCEPROP 1 LAST BODY_TYPE PLUMBING
J 2
(2900 2275);
DISPLAY 0.872340 (2900 2275);
PAINT GREEN (2900 2275);
DISPLAY INVISIBLE (2900 2275);
FORCEPROP 1 LAST HDL_TAP TRUE
J 2
(2575 2100);
DISPLAY 0.872340 (2575 2100);
DISPLAY INVISIBLE (2575 2100);
FORCEPROP 1 LAST PATH I149
J 2
(2902 2225);
DISPLAY 0.872340 (2902 2225);
PAINT GREEN (2902 2225);
DISPLAY INVISIBLE (2902 2225);
FORCEADD TAP..1
R 2
(2900 2425);
FORCEPROP 3 LASTPIN (2950 2425) SIG_NAME P5E_CPU1_P2_TX_DN<9>
J 0
(2960 2435);
DISPLAY 0.659574 (2960 2435);
PAINT MONO (2960 2435);
DISPLAY INVISIBLE (2960 2435);
FORCEPROP 1 LASTPIN (2950 2425) BN 9
J 2
(2962 2433);
DISPLAY 0.680851 (2962 2433);
PAINT GREEN (2962 2433);
FORCEPROP 2 LAST CDS_LIB standard
J 0
(2900 2425);
DISPLAY INVISIBLE (2900 2425);
FORCEPROP 1 LAST BODY_TYPE PLUMBING
J 2
(2900 2475);
DISPLAY 0.872340 (2900 2475);
PAINT GREEN (2900 2475);
DISPLAY INVISIBLE (2900 2475);
FORCEPROP 1 LAST HDL_TAP TRUE
J 2
(2575 2300);
DISPLAY 0.872340 (2575 2300);
DISPLAY INVISIBLE (2575 2300);
FORCEPROP 1 LAST PATH I150
J 2
(2902 2425);
DISPLAY 0.872340 (2902 2425);
PAINT GREEN (2902 2425);
DISPLAY INVISIBLE (2902 2425);
FORCEADD TAP..1
R 2
(2900 2625);
FORCEPROP 3 LASTPIN (2950 2625) SIG_NAME P5E_CPU1_P2_TX_DN<10>
J 0
(2960 2635);
DISPLAY 0.659574 (2960 2635);
PAINT MONO (2960 2635);
DISPLAY INVISIBLE (2960 2635);
FORCEPROP 1 LASTPIN (2950 2625) BN 10
J 2
(2962 2633);
DISPLAY 0.680851 (2962 2633);
PAINT GREEN (2962 2633);
FORCEPROP 2 LAST CDS_LIB standard
J 0
(2900 2625);
DISPLAY INVISIBLE (2900 2625);
FORCEPROP 1 LAST BODY_TYPE PLUMBING
J 2
(2900 2675);
DISPLAY 0.872340 (2900 2675);
PAINT GREEN (2900 2675);
DISPLAY INVISIBLE (2900 2675);
FORCEPROP 1 LAST HDL_TAP TRUE
J 2
(2575 2500);
DISPLAY 0.872340 (2575 2500);
DISPLAY INVISIBLE (2575 2500);
FORCEPROP 1 LAST PATH I151
J 2
(2902 2625);
DISPLAY 0.872340 (2902 2625);
PAINT GREEN (2902 2625);
DISPLAY INVISIBLE (2902 2625);
FORCEADD TAP..1
R 2
(2900 2825);
FORCEPROP 3 LASTPIN (2950 2825) SIG_NAME P5E_CPU1_P2_TX_DN<11>
J 0
(2960 2835);
DISPLAY 0.659574 (2960 2835);
PAINT MONO (2960 2835);
DISPLAY INVISIBLE (2960 2835);
FORCEPROP 1 LASTPIN (2950 2825) BN 11
J 2
(2962 2833);
DISPLAY 0.680851 (2962 2833);
PAINT GREEN (2962 2833);
FORCEPROP 2 LAST CDS_LIB standard
J 0
(2900 2825);
DISPLAY INVISIBLE (2900 2825);
FORCEPROP 1 LAST BODY_TYPE PLUMBING
J 2
(2900 2875);
DISPLAY 0.872340 (2900 2875);
PAINT GREEN (2900 2875);
DISPLAY INVISIBLE (2900 2875);
FORCEPROP 1 LAST HDL_TAP TRUE
J 2
(2575 2700);
DISPLAY 0.872340 (2575 2700);
DISPLAY INVISIBLE (2575 2700);
FORCEPROP 1 LAST PATH I152
J 2
(2902 2825);
DISPLAY 0.872340 (2902 2825);
PAINT GREEN (2902 2825);
DISPLAY INVISIBLE (2902 2825);
FORCEADD TAP..1
R 2
(2900 3025);
FORCEPROP 3 LASTPIN (2950 3025) SIG_NAME P5E_CPU1_P2_TX_DN<12>
J 0
(2960 3035);
DISPLAY 0.659574 (2960 3035);
PAINT MONO (2960 3035);
DISPLAY INVISIBLE (2960 3035);
FORCEPROP 1 LASTPIN (2950 3025) BN 12
J 2
(2962 3033);
DISPLAY 0.680851 (2962 3033);
PAINT GREEN (2962 3033);
FORCEPROP 2 LAST CDS_LIB standard
J 0
(2900 3025);
DISPLAY INVISIBLE (2900 3025);
FORCEPROP 1 LAST BODY_TYPE PLUMBING
J 2
(2900 3075);
DISPLAY 0.872340 (2900 3075);
PAINT GREEN (2900 3075);
DISPLAY INVISIBLE (2900 3075);
FORCEPROP 1 LAST HDL_TAP TRUE
J 2
(2575 2900);
DISPLAY 0.872340 (2575 2900);
DISPLAY INVISIBLE (2575 2900);
FORCEPROP 1 LAST PATH I153
J 2
(2902 3025);
DISPLAY 0.872340 (2902 3025);
PAINT GREEN (2902 3025);
DISPLAY INVISIBLE (2902 3025);
FORCEADD Q_CAP_DIFFBUS..2
R 2
(3625 2225);
FORCEPROP 1 LAST LOCATION C756
J 2
(3859 2242);
DISPLAY 0.723404 (3859 2242);
PAINT GREEN (3859 2242);
FORCEPROP 2 LAST $SEC 1
J 2
(3800 2300);
DISPLAY 0.680851 (3800 2300);
PAINT MONO (3800 2300);
DISPLAY INVISIBLE (3800 2300);
FORCEPROP 2 LAST CDS_SEC 1
J 2
(3800 2300);
DISPLAY 0.680851 (3800 2300);
DISPLAY INVISIBLE (3800 2300);
FORCEPROP 2 LASTPIN (3700 2225) $PN 1
J 0
(3710 2235);
DISPLAY 0.808511 (3710 2235);
FORCEPROP 2 LASTPIN (3550 2225) $PN 2
J 2
(3540 2235);
DISPLAY 0.808511 (3540 2235);
FORCEPROP 2 LAST VALUE DIFF BUS_0.22UF
J 2
(3475 2225);
DISPLAY 0.553191 (3475 2225);
FORCEPROP 1 LAST CDS_LMAN_SYM_OUTLINE -25,50,25,-50
J 2
(3625 2225);
DISPLAY 0.468085 (3625 2225);
PAINT GREEN (3625 2225);
DISPLAY INVISIBLE (3625 2225);
FORCEPROP 2 LAST CDS_LIB pure_quanta
J 2
(3625 2225);
DISPLAY INVISIBLE (3625 2225);
FORCEPROP 1 LAST PIN_NAMES_ROTATE TRUE
J 2
(3625 2225);
DISPLAY 0.489362 (3625 2225);
PAINT GREEN (3625 2225);
DISPLAY INVISIBLE (3625 2225);
FORCEPROP 2 LAST VOLTAGE 6.3V
J 2
(3275 2275);
DISPLAY 0.553191 (3275 2275);
DISPLAY INVISIBLE (3275 2275);
FORCEPROP 1 LAST MATERIAL X6S
J 2
(3634 2304);
DISPLAY 0.574468 (3634 2304);
PAINT GREEN (3634 2304);
DISPLAY INVISIBLE (3634 2304);
FORCEPROP 2 LAST PACK_TYPE C0201
J 2
(3450 2275);
DISPLAY 0.553191 (3450 2275);
DISPLAY INVISIBLE (3450 2275);
FORCEPROP 2 LAST TOLERANCE 20%
J 2
(3550 2275);
DISPLAY 0.553191 (3550 2275);
DISPLAY INVISIBLE (3550 2275);
FORCEPROP 1 LAST PART_NUMBER SP_CH4221MEE01
J 2
(3509 2313);
DISPLAY 0.574468 (3509 2313);
PAINT GREEN (3509 2313);
DISPLAY INVISIBLE (3509 2313);
FORCEPROP 1 LAST LOCATION C756
J 0
(3875 2300);
DISPLAY 1.021277 (3875 2300);
DISPLAY INVISIBLE (3875 2300);
FORCEPROP 1 LAST PATH I154
J 2
(3625 2225);
DISPLAY 0.723404 (3625 2225);
DISPLAY INVISIBLE (3625 2225);
FORCEADD Q_CAP_DIFFBUS..2
R 2
(3625 2175);
FORCEPROP 1 LAST LOCATION C757
J 2
(3859 2192);
DISPLAY 0.723404 (3859 2192);
PAINT GREEN (3859 2192);
FORCEPROP 2 LAST $SEC 1
J 2
(3800 2250);
DISPLAY 0.680851 (3800 2250);
PAINT MONO (3800 2250);
DISPLAY INVISIBLE (3800 2250);
FORCEPROP 2 LAST CDS_SEC 1
J 2
(3800 2250);
DISPLAY 0.680851 (3800 2250);
DISPLAY INVISIBLE (3800 2250);
FORCEPROP 2 LASTPIN (3700 2175) $PN 1
J 0
(3710 2185);
DISPLAY 0.808511 (3710 2185);
FORCEPROP 2 LASTPIN (3550 2175) $PN 2
J 2
(3540 2185);
DISPLAY 0.808511 (3540 2185);
FORCEPROP 2 LAST VALUE DIFF BUS_0.22UF
J 2
(3475 2175);
DISPLAY 0.553191 (3475 2175);
FORCEPROP 1 LAST CDS_LMAN_SYM_OUTLINE -25,50,25,-50
J 2
(3625 2175);
DISPLAY 0.468085 (3625 2175);
PAINT GREEN (3625 2175);
DISPLAY INVISIBLE (3625 2175);
FORCEPROP 2 LAST CDS_LIB pure_quanta
J 2
(3625 2175);
DISPLAY INVISIBLE (3625 2175);
FORCEPROP 1 LAST PIN_NAMES_ROTATE TRUE
J 2
(3625 2175);
DISPLAY 0.489362 (3625 2175);
PAINT GREEN (3625 2175);
DISPLAY INVISIBLE (3625 2175);
FORCEPROP 2 LAST VOLTAGE 6.3V
J 2
(3275 2225);
DISPLAY 0.553191 (3275 2225);
DISPLAY INVISIBLE (3275 2225);
FORCEPROP 1 LAST MATERIAL X6S
J 2
(3634 2254);
DISPLAY 0.574468 (3634 2254);
PAINT GREEN (3634 2254);
DISPLAY INVISIBLE (3634 2254);
FORCEPROP 2 LAST PACK_TYPE C0201
J 2
(3450 2225);
DISPLAY 0.553191 (3450 2225);
DISPLAY INVISIBLE (3450 2225);
FORCEPROP 2 LAST TOLERANCE 20%
J 2
(3550 2225);
DISPLAY 0.553191 (3550 2225);
DISPLAY INVISIBLE (3550 2225);
FORCEPROP 1 LAST PART_NUMBER SP_CH4221MEE01
J 2
(3509 2263);
DISPLAY 0.574468 (3509 2263);
PAINT GREEN (3509 2263);
DISPLAY INVISIBLE (3509 2263);
FORCEPROP 1 LAST LOCATION C757
J 0
(3875 2250);
DISPLAY 1.021277 (3875 2250);
DISPLAY INVISIBLE (3875 2250);
FORCEPROP 1 LAST PATH I155
J 2
(3625 2175);
DISPLAY 0.723404 (3625 2175);
DISPLAY INVISIBLE (3625 2175);
FORCEADD Q_CAP_DIFFBUS..2
R 2
(3625 2375);
FORCEPROP 1 LAST LOCATION C755
J 2
(3859 2392);
DISPLAY 0.723404 (3859 2392);
PAINT GREEN (3859 2392);
FORCEPROP 2 LAST $SEC 1
J 2
(3800 2450);
DISPLAY 0.680851 (3800 2450);
PAINT MONO (3800 2450);
DISPLAY INVISIBLE (3800 2450);
FORCEPROP 2 LAST CDS_SEC 1
J 2
(3800 2450);
DISPLAY 0.680851 (3800 2450);
DISPLAY INVISIBLE (3800 2450);
FORCEPROP 2 LASTPIN (3700 2375) $PN 1
J 0
(3710 2385);
DISPLAY 0.808511 (3710 2385);
FORCEPROP 2 LASTPIN (3550 2375) $PN 2
J 2
(3540 2385);
DISPLAY 0.808511 (3540 2385);
FORCEPROP 2 LAST VALUE DIFF BUS_0.22UF
J 2
(3475 2375);
DISPLAY 0.553191 (3475 2375);
FORCEPROP 1 LAST CDS_LMAN_SYM_OUTLINE -25,50,25,-50
J 2
(3625 2375);
DISPLAY 0.468085 (3625 2375);
PAINT GREEN (3625 2375);
DISPLAY INVISIBLE (3625 2375);
FORCEPROP 2 LAST CDS_LIB pure_quanta
J 2
(3625 2375);
DISPLAY INVISIBLE (3625 2375);
FORCEPROP 1 LAST PIN_NAMES_ROTATE TRUE
J 2
(3625 2375);
DISPLAY 0.489362 (3625 2375);
PAINT GREEN (3625 2375);
DISPLAY INVISIBLE (3625 2375);
FORCEPROP 2 LAST VOLTAGE 6.3V
J 2
(3275 2425);
DISPLAY 0.553191 (3275 2425);
DISPLAY INVISIBLE (3275 2425);
FORCEPROP 1 LAST MATERIAL X6S
J 2
(3634 2454);
DISPLAY 0.574468 (3634 2454);
PAINT GREEN (3634 2454);
DISPLAY INVISIBLE (3634 2454);
FORCEPROP 2 LAST PACK_TYPE C0201
J 2
(3450 2425);
DISPLAY 0.553191 (3450 2425);
DISPLAY INVISIBLE (3450 2425);
FORCEPROP 2 LAST TOLERANCE 20%
J 2
(3550 2425);
DISPLAY 0.553191 (3550 2425);
DISPLAY INVISIBLE (3550 2425);
FORCEPROP 1 LAST PART_NUMBER SP_CH4221MEE01
J 2
(3509 2463);
DISPLAY 0.574468 (3509 2463);
PAINT GREEN (3509 2463);
DISPLAY INVISIBLE (3509 2463);
FORCEPROP 1 LAST LOCATION C755
J 0
(3875 2450);
DISPLAY 1.021277 (3875 2450);
DISPLAY INVISIBLE (3875 2450);
FORCEPROP 1 LAST PATH I156
J 2
(3625 2375);
DISPLAY 0.723404 (3625 2375);
DISPLAY INVISIBLE (3625 2375);
FORCEADD Q_CAP_DIFFBUS..2
R 2
(3625 2425);
FORCEPROP 1 LAST LOCATION C754
J 2
(3859 2442);
DISPLAY 0.723404 (3859 2442);
PAINT GREEN (3859 2442);
FORCEPROP 2 LAST $SEC 1
J 2
(3800 2500);
DISPLAY 0.680851 (3800 2500);
PAINT MONO (3800 2500);
DISPLAY INVISIBLE (3800 2500);
FORCEPROP 2 LAST CDS_SEC 1
J 2
(3800 2500);
DISPLAY 0.680851 (3800 2500);
DISPLAY INVISIBLE (3800 2500);
FORCEPROP 2 LASTPIN (3700 2425) $PN 1
J 0
(3710 2435);
DISPLAY 0.808511 (3710 2435);
FORCEPROP 2 LASTPIN (3550 2425) $PN 2
J 2
(3540 2435);
DISPLAY 0.808511 (3540 2435);
FORCEPROP 2 LAST VALUE DIFF BUS_0.22UF
J 2
(3475 2425);
DISPLAY 0.553191 (3475 2425);
FORCEPROP 2 LAST CDS_LIB pure_quanta
J 2
(3625 2425);
DISPLAY INVISIBLE (3625 2425);
FORCEPROP 1 LAST CDS_LMAN_SYM_OUTLINE -25,50,25,-50
J 2
(3625 2425);
DISPLAY 0.468085 (3625 2425);
PAINT GREEN (3625 2425);
DISPLAY INVISIBLE (3625 2425);
FORCEPROP 1 LAST PIN_NAMES_ROTATE TRUE
J 2
(3625 2425);
DISPLAY 0.489362 (3625 2425);
PAINT GREEN (3625 2425);
DISPLAY INVISIBLE (3625 2425);
FORCEPROP 2 LAST VOLTAGE 6.3V
J 2
(3275 2475);
DISPLAY 0.553191 (3275 2475);
DISPLAY INVISIBLE (3275 2475);
FORCEPROP 1 LAST MATERIAL X6S
J 2
(3634 2504);
DISPLAY 0.574468 (3634 2504);
PAINT GREEN (3634 2504);
DISPLAY INVISIBLE (3634 2504);
FORCEPROP 2 LAST PACK_TYPE C0201
J 2
(3450 2475);
DISPLAY 0.553191 (3450 2475);
DISPLAY INVISIBLE (3450 2475);
FORCEPROP 2 LAST TOLERANCE 20%
J 2
(3550 2475);
DISPLAY 0.553191 (3550 2475);
DISPLAY INVISIBLE (3550 2475);
FORCEPROP 1 LAST PART_NUMBER SP_CH4221MEE01
J 2
(3509 2513);
DISPLAY 0.574468 (3509 2513);
PAINT GREEN (3509 2513);
DISPLAY INVISIBLE (3509 2513);
FORCEPROP 1 LAST LOCATION C754
J 0
(3875 2500);
DISPLAY 1.021277 (3875 2500);
DISPLAY INVISIBLE (3875 2500);
FORCEPROP 1 LAST PATH I157
J 2
(3625 2425);
DISPLAY 0.723404 (3625 2425);
DISPLAY INVISIBLE (3625 2425);
FORCEADD Q_CAP_DIFFBUS..2
R 2
(3625 2575);
FORCEPROP 1 LAST LOCATION C753
J 2
(3859 2592);
DISPLAY 0.723404 (3859 2592);
PAINT GREEN (3859 2592);
FORCEPROP 2 LAST $SEC 1
J 2
(3800 2650);
DISPLAY 0.680851 (3800 2650);
PAINT MONO (3800 2650);
DISPLAY INVISIBLE (3800 2650);
FORCEPROP 2 LAST CDS_SEC 1
J 2
(3800 2650);
DISPLAY 0.680851 (3800 2650);
DISPLAY INVISIBLE (3800 2650);
FORCEPROP 2 LASTPIN (3700 2575) $PN 1
J 0
(3710 2585);
DISPLAY 0.808511 (3710 2585);
FORCEPROP 2 LASTPIN (3550 2575) $PN 2
J 2
(3540 2585);
DISPLAY 0.808511 (3540 2585);
FORCEPROP 2 LAST VALUE DIFF BUS_0.22UF
J 2
(3475 2575);
DISPLAY 0.553191 (3475 2575);
FORCEPROP 1 LAST CDS_LMAN_SYM_OUTLINE -25,50,25,-50
J 2
(3625 2575);
DISPLAY 0.468085 (3625 2575);
PAINT GREEN (3625 2575);
DISPLAY INVISIBLE (3625 2575);
FORCEPROP 2 LAST CDS_LIB pure_quanta
J 2
(3625 2575);
DISPLAY INVISIBLE (3625 2575);
FORCEPROP 1 LAST PIN_NAMES_ROTATE TRUE
J 2
(3625 2575);
DISPLAY 0.489362 (3625 2575);
PAINT GREEN (3625 2575);
DISPLAY INVISIBLE (3625 2575);
FORCEPROP 2 LAST VOLTAGE 6.3V
J 2
(3275 2625);
DISPLAY 0.553191 (3275 2625);
DISPLAY INVISIBLE (3275 2625);
FORCEPROP 1 LAST MATERIAL X6S
J 2
(3634 2654);
DISPLAY 0.574468 (3634 2654);
PAINT GREEN (3634 2654);
DISPLAY INVISIBLE (3634 2654);
FORCEPROP 2 LAST PACK_TYPE C0201
J 2
(3450 2625);
DISPLAY 0.553191 (3450 2625);
DISPLAY INVISIBLE (3450 2625);
FORCEPROP 2 LAST TOLERANCE 20%
J 2
(3550 2625);
DISPLAY 0.553191 (3550 2625);
DISPLAY INVISIBLE (3550 2625);
FORCEPROP 1 LAST PART_NUMBER SP_CH4221MEE01
J 2
(3509 2663);
DISPLAY 0.574468 (3509 2663);
PAINT GREEN (3509 2663);
DISPLAY INVISIBLE (3509 2663);
FORCEPROP 1 LAST LOCATION C753
J 0
(3875 2650);
DISPLAY 1.021277 (3875 2650);
DISPLAY INVISIBLE (3875 2650);
FORCEPROP 1 LAST PATH I158
J 2
(3625 2575);
DISPLAY 0.723404 (3625 2575);
DISPLAY INVISIBLE (3625 2575);
FORCEADD Q_CAP_DIFFBUS..2
R 2
(3625 2625);
FORCEPROP 1 LAST LOCATION C752
J 2
(3859 2642);
DISPLAY 0.723404 (3859 2642);
PAINT GREEN (3859 2642);
FORCEPROP 2 LAST $SEC 1
J 2
(3800 2700);
DISPLAY 0.680851 (3800 2700);
PAINT MONO (3800 2700);
DISPLAY INVISIBLE (3800 2700);
FORCEPROP 2 LAST CDS_SEC 1
J 2
(3800 2700);
DISPLAY 0.680851 (3800 2700);
DISPLAY INVISIBLE (3800 2700);
FORCEPROP 2 LASTPIN (3700 2625) $PN 1
J 0
(3710 2635);
DISPLAY 0.808511 (3710 2635);
FORCEPROP 2 LASTPIN (3550 2625) $PN 2
J 2
(3540 2635);
DISPLAY 0.808511 (3540 2635);
FORCEPROP 2 LAST VALUE DIFF BUS_0.22UF
J 2
(3475 2625);
DISPLAY 0.553191 (3475 2625);
FORCEPROP 1 LAST CDS_LMAN_SYM_OUTLINE -25,50,25,-50
J 2
(3625 2625);
DISPLAY 0.468085 (3625 2625);
PAINT GREEN (3625 2625);
DISPLAY INVISIBLE (3625 2625);
FORCEPROP 2 LAST CDS_LIB pure_quanta
J 2
(3625 2625);
DISPLAY INVISIBLE (3625 2625);
FORCEPROP 1 LAST PIN_NAMES_ROTATE TRUE
J 2
(3625 2625);
DISPLAY 0.489362 (3625 2625);
PAINT GREEN (3625 2625);
DISPLAY INVISIBLE (3625 2625);
FORCEPROP 2 LAST VOLTAGE 6.3V
J 2
(3275 2675);
DISPLAY 0.553191 (3275 2675);
DISPLAY INVISIBLE (3275 2675);
FORCEPROP 1 LAST MATERIAL X6S
J 2
(3634 2704);
DISPLAY 0.574468 (3634 2704);
PAINT GREEN (3634 2704);
DISPLAY INVISIBLE (3634 2704);
FORCEPROP 2 LAST PACK_TYPE C0201
J 2
(3450 2675);
DISPLAY 0.553191 (3450 2675);
DISPLAY INVISIBLE (3450 2675);
FORCEPROP 2 LAST TOLERANCE 20%
J 2
(3550 2675);
DISPLAY 0.553191 (3550 2675);
DISPLAY INVISIBLE (3550 2675);
FORCEPROP 1 LAST PART_NUMBER SP_CH4221MEE01
J 2
(3509 2713);
DISPLAY 0.574468 (3509 2713);
PAINT GREEN (3509 2713);
DISPLAY INVISIBLE (3509 2713);
FORCEPROP 1 LAST LOCATION C752
J 0
(3875 2700);
DISPLAY 1.021277 (3875 2700);
DISPLAY INVISIBLE (3875 2700);
FORCEPROP 1 LAST PATH I159
J 2
(3625 2625);
DISPLAY 0.723404 (3625 2625);
DISPLAY INVISIBLE (3625 2625);
FORCEADD Q_CAP_DIFFBUS..2
R 2
(3625 2825);
FORCEPROP 1 LAST LOCATION C750
J 2
(3859 2842);
DISPLAY 0.723404 (3859 2842);
PAINT GREEN (3859 2842);
FORCEPROP 2 LAST $SEC 1
J 2
(3800 2900);
DISPLAY 0.680851 (3800 2900);
PAINT MONO (3800 2900);
DISPLAY INVISIBLE (3800 2900);
FORCEPROP 2 LAST CDS_SEC 1
J 2
(3800 2900);
DISPLAY 0.680851 (3800 2900);
DISPLAY INVISIBLE (3800 2900);
FORCEPROP 2 LASTPIN (3700 2825) $PN 1
J 0
(3710 2835);
DISPLAY 0.808511 (3710 2835);
FORCEPROP 2 LASTPIN (3550 2825) $PN 2
J 2
(3540 2835);
DISPLAY 0.808511 (3540 2835);
FORCEPROP 2 LAST VALUE DIFF BUS_0.22UF
J 2
(3475 2825);
DISPLAY 0.553191 (3475 2825);
FORCEPROP 2 LAST CDS_LIB pure_quanta
J 2
(3625 2825);
DISPLAY INVISIBLE (3625 2825);
FORCEPROP 1 LAST CDS_LMAN_SYM_OUTLINE -25,50,25,-50
J 2
(3625 2825);
DISPLAY 0.468085 (3625 2825);
PAINT GREEN (3625 2825);
DISPLAY INVISIBLE (3625 2825);
FORCEPROP 1 LAST PIN_NAMES_ROTATE TRUE
J 2
(3625 2825);
DISPLAY 0.489362 (3625 2825);
PAINT GREEN (3625 2825);
DISPLAY INVISIBLE (3625 2825);
FORCEPROP 2 LAST VOLTAGE 6.3V
J 2
(3275 2875);
DISPLAY 0.553191 (3275 2875);
DISPLAY INVISIBLE (3275 2875);
FORCEPROP 1 LAST MATERIAL X6S
J 2
(3634 2904);
DISPLAY 0.574468 (3634 2904);
PAINT GREEN (3634 2904);
DISPLAY INVISIBLE (3634 2904);
FORCEPROP 2 LAST PACK_TYPE C0201
J 2
(3450 2875);
DISPLAY 0.553191 (3450 2875);
DISPLAY INVISIBLE (3450 2875);
FORCEPROP 2 LAST TOLERANCE 20%
J 2
(3550 2875);
DISPLAY 0.553191 (3550 2875);
DISPLAY INVISIBLE (3550 2875);
FORCEPROP 1 LAST PART_NUMBER SP_CH4221MEE01
J 2
(3509 2913);
DISPLAY 0.574468 (3509 2913);
PAINT GREEN (3509 2913);
DISPLAY INVISIBLE (3509 2913);
FORCEPROP 1 LAST LOCATION C750
J 0
(3875 2900);
DISPLAY 1.021277 (3875 2900);
DISPLAY INVISIBLE (3875 2900);
FORCEPROP 1 LAST PATH I160
J 2
(3625 2825);
DISPLAY 0.723404 (3625 2825);
DISPLAY INVISIBLE (3625 2825);
FORCEADD Q_CAP_DIFFBUS..2
R 2
(3625 2775);
FORCEPROP 1 LAST LOCATION C751
J 2
(3859 2792);
DISPLAY 0.723404 (3859 2792);
PAINT GREEN (3859 2792);
FORCEPROP 2 LAST $SEC 1
J 2
(3800 2850);
DISPLAY 0.680851 (3800 2850);
PAINT MONO (3800 2850);
DISPLAY INVISIBLE (3800 2850);
FORCEPROP 2 LAST CDS_SEC 1
J 2
(3800 2850);
DISPLAY 0.680851 (3800 2850);
DISPLAY INVISIBLE (3800 2850);
FORCEPROP 2 LASTPIN (3700 2775) $PN 1
J 0
(3710 2785);
DISPLAY 0.808511 (3710 2785);
FORCEPROP 2 LASTPIN (3550 2775) $PN 2
J 2
(3540 2785);
DISPLAY 0.808511 (3540 2785);
FORCEPROP 2 LAST VALUE DIFF BUS_0.22UF
J 2
(3475 2775);
DISPLAY 0.553191 (3475 2775);
FORCEPROP 2 LAST CDS_LIB pure_quanta
J 2
(3625 2775);
DISPLAY INVISIBLE (3625 2775);
FORCEPROP 1 LAST CDS_LMAN_SYM_OUTLINE -25,50,25,-50
J 2
(3625 2775);
DISPLAY 0.468085 (3625 2775);
PAINT GREEN (3625 2775);
DISPLAY INVISIBLE (3625 2775);
FORCEPROP 1 LAST PIN_NAMES_ROTATE TRUE
J 2
(3625 2775);
DISPLAY 0.489362 (3625 2775);
PAINT GREEN (3625 2775);
DISPLAY INVISIBLE (3625 2775);
FORCEPROP 2 LAST VOLTAGE 6.3V
J 2
(3275 2825);
DISPLAY 0.553191 (3275 2825);
DISPLAY INVISIBLE (3275 2825);
FORCEPROP 1 LAST MATERIAL X6S
J 2
(3634 2854);
DISPLAY 0.574468 (3634 2854);
PAINT GREEN (3634 2854);
DISPLAY INVISIBLE (3634 2854);
FORCEPROP 2 LAST PACK_TYPE C0201
J 2
(3450 2825);
DISPLAY 0.553191 (3450 2825);
DISPLAY INVISIBLE (3450 2825);
FORCEPROP 2 LAST TOLERANCE 20%
J 2
(3550 2825);
DISPLAY 0.553191 (3550 2825);
DISPLAY INVISIBLE (3550 2825);
FORCEPROP 1 LAST PART_NUMBER SP_CH4221MEE01
J 2
(3509 2863);
DISPLAY 0.574468 (3509 2863);
PAINT GREEN (3509 2863);
DISPLAY INVISIBLE (3509 2863);
FORCEPROP 1 LAST LOCATION C751
J 0
(3875 2850);
DISPLAY 1.021277 (3875 2850);
DISPLAY INVISIBLE (3875 2850);
FORCEPROP 1 LAST PATH I161
J 2
(3625 2775);
DISPLAY 0.723404 (3625 2775);
DISPLAY INVISIBLE (3625 2775);
FORCEADD Q_CAP_DIFFBUS..2
R 2
(3625 2975);
FORCEPROP 1 LAST LOCATION C749
J 2
(3859 2992);
DISPLAY 0.723404 (3859 2992);
PAINT GREEN (3859 2992);
FORCEPROP 2 LAST $SEC 1
J 2
(3800 3050);
DISPLAY 0.680851 (3800 3050);
PAINT MONO (3800 3050);
DISPLAY INVISIBLE (3800 3050);
FORCEPROP 2 LAST CDS_SEC 1
J 2
(3800 3050);
DISPLAY 0.680851 (3800 3050);
DISPLAY INVISIBLE (3800 3050);
FORCEPROP 2 LASTPIN (3700 2975) $PN 1
J 0
(3710 2985);
DISPLAY 0.808511 (3710 2985);
FORCEPROP 2 LASTPIN (3550 2975) $PN 2
J 2
(3540 2985);
DISPLAY 0.808511 (3540 2985);
FORCEPROP 2 LAST VALUE DIFF BUS_0.22UF
J 2
(3475 2975);
DISPLAY 0.553191 (3475 2975);
FORCEPROP 1 LAST CDS_LMAN_SYM_OUTLINE -25,50,25,-50
J 2
(3625 2975);
DISPLAY 0.468085 (3625 2975);
PAINT GREEN (3625 2975);
DISPLAY INVISIBLE (3625 2975);
FORCEPROP 2 LAST CDS_LIB pure_quanta
J 2
(3625 2975);
DISPLAY INVISIBLE (3625 2975);
FORCEPROP 1 LAST PIN_NAMES_ROTATE TRUE
J 2
(3625 2975);
DISPLAY 0.489362 (3625 2975);
PAINT GREEN (3625 2975);
DISPLAY INVISIBLE (3625 2975);
FORCEPROP 2 LAST VOLTAGE 6.3V
J 2
(3275 3025);
DISPLAY 0.553191 (3275 3025);
DISPLAY INVISIBLE (3275 3025);
FORCEPROP 1 LAST MATERIAL X6S
J 2
(3634 3054);
DISPLAY 0.574468 (3634 3054);
PAINT GREEN (3634 3054);
DISPLAY INVISIBLE (3634 3054);
FORCEPROP 2 LAST PACK_TYPE C0201
J 2
(3450 3025);
DISPLAY 0.553191 (3450 3025);
DISPLAY INVISIBLE (3450 3025);
FORCEPROP 2 LAST TOLERANCE 20%
J 2
(3550 3025);
DISPLAY 0.553191 (3550 3025);
DISPLAY INVISIBLE (3550 3025);
FORCEPROP 1 LAST PART_NUMBER SP_CH4221MEE01
J 2
(3509 3063);
DISPLAY 0.574468 (3509 3063);
PAINT GREEN (3509 3063);
DISPLAY INVISIBLE (3509 3063);
FORCEPROP 1 LAST LOCATION C749
J 0
(3875 3050);
DISPLAY 1.021277 (3875 3050);
DISPLAY INVISIBLE (3875 3050);
FORCEPROP 1 LAST PATH I162
J 2
(3625 2975);
DISPLAY 0.723404 (3625 2975);
DISPLAY INVISIBLE (3625 2975);
FORCEADD Q_CAP_DIFFBUS..2
R 2
(3625 3025);
FORCEPROP 1 LAST LOCATION C748
J 2
(3859 3042);
DISPLAY 0.723404 (3859 3042);
PAINT GREEN (3859 3042);
FORCEPROP 2 LAST $SEC 1
J 2
(3800 3100);
DISPLAY 0.680851 (3800 3100);
PAINT MONO (3800 3100);
DISPLAY INVISIBLE (3800 3100);
FORCEPROP 2 LAST CDS_SEC 1
J 2
(3800 3100);
DISPLAY 0.680851 (3800 3100);
DISPLAY INVISIBLE (3800 3100);
FORCEPROP 2 LASTPIN (3700 3025) $PN 1
J 0
(3710 3035);
DISPLAY 0.808511 (3710 3035);
FORCEPROP 2 LASTPIN (3550 3025) $PN 2
J 2
(3540 3035);
DISPLAY 0.808511 (3540 3035);
FORCEPROP 2 LAST VALUE DIFF BUS_0.22UF
J 2
(3475 3025);
DISPLAY 0.553191 (3475 3025);
FORCEPROP 1 LAST CDS_LMAN_SYM_OUTLINE -25,50,25,-50
J 2
(3625 3025);
DISPLAY 0.468085 (3625 3025);
PAINT GREEN (3625 3025);
DISPLAY INVISIBLE (3625 3025);
FORCEPROP 2 LAST CDS_LIB pure_quanta
J 2
(3625 3025);
DISPLAY INVISIBLE (3625 3025);
FORCEPROP 1 LAST PIN_NAMES_ROTATE TRUE
J 2
(3625 3025);
DISPLAY 0.489362 (3625 3025);
PAINT GREEN (3625 3025);
DISPLAY INVISIBLE (3625 3025);
FORCEPROP 2 LAST VOLTAGE 6.3V
J 2
(3275 3075);
DISPLAY 0.553191 (3275 3075);
DISPLAY INVISIBLE (3275 3075);
FORCEPROP 1 LAST MATERIAL X6S
J 2
(3634 3104);
DISPLAY 0.574468 (3634 3104);
PAINT GREEN (3634 3104);
DISPLAY INVISIBLE (3634 3104);
FORCEPROP 2 LAST PACK_TYPE C0201
J 2
(3450 3075);
DISPLAY 0.553191 (3450 3075);
DISPLAY INVISIBLE (3450 3075);
FORCEPROP 2 LAST TOLERANCE 20%
J 2
(3550 3075);
DISPLAY 0.553191 (3550 3075);
DISPLAY INVISIBLE (3550 3075);
FORCEPROP 1 LAST PART_NUMBER SP_CH4221MEE01
J 2
(3509 3113);
DISPLAY 0.574468 (3509 3113);
PAINT GREEN (3509 3113);
DISPLAY INVISIBLE (3509 3113);
FORCEPROP 1 LAST LOCATION C748
J 0
(3875 3100);
DISPLAY 1.021277 (3875 3100);
DISPLAY INVISIBLE (3875 3100);
FORCEPROP 1 LAST PATH I163
J 2
(3625 3025);
DISPLAY 0.723404 (3625 3025);
DISPLAY INVISIBLE (3625 3025);
FORCEADD TAP..1
R 2
(2900 3225);
FORCEPROP 3 LASTPIN (2950 3225) SIG_NAME P5E_CPU1_P2_TX_DN<13>
J 0
(2960 3235);
DISPLAY 0.659574 (2960 3235);
PAINT MONO (2960 3235);
DISPLAY INVISIBLE (2960 3235);
FORCEPROP 1 LASTPIN (2950 3225) BN 13
J 2
(2962 3233);
DISPLAY 0.680851 (2962 3233);
PAINT GREEN (2962 3233);
FORCEPROP 2 LAST CDS_LIB standard
J 0
(2900 3225);
DISPLAY INVISIBLE (2900 3225);
FORCEPROP 1 LAST BODY_TYPE PLUMBING
J 2
(2900 3275);
DISPLAY 0.872340 (2900 3275);
PAINT GREEN (2900 3275);
DISPLAY INVISIBLE (2900 3275);
FORCEPROP 1 LAST HDL_TAP TRUE
J 2
(2575 3100);
DISPLAY 0.872340 (2575 3100);
DISPLAY INVISIBLE (2575 3100);
FORCEPROP 1 LAST PATH I164
J 2
(2902 3225);
DISPLAY 0.872340 (2902 3225);
PAINT GREEN (2902 3225);
DISPLAY INVISIBLE (2902 3225);
FORCEADD TAP..1
R 2
(2900 3425);
FORCEPROP 3 LASTPIN (2950 3425) SIG_NAME P5E_CPU1_P2_TX_DN<14>
J 0
(2960 3435);
DISPLAY 0.659574 (2960 3435);
PAINT MONO (2960 3435);
DISPLAY INVISIBLE (2960 3435);
FORCEPROP 1 LASTPIN (2950 3425) BN 14
J 2
(2962 3433);
DISPLAY 0.680851 (2962 3433);
PAINT GREEN (2962 3433);
FORCEPROP 2 LAST CDS_LIB standard
J 0
(2900 3425);
DISPLAY INVISIBLE (2900 3425);
FORCEPROP 1 LAST BODY_TYPE PLUMBING
J 2
(2900 3475);
DISPLAY 0.872340 (2900 3475);
PAINT GREEN (2900 3475);
DISPLAY INVISIBLE (2900 3475);
FORCEPROP 1 LAST HDL_TAP TRUE
J 2
(2575 3300);
DISPLAY 0.872340 (2575 3300);
DISPLAY INVISIBLE (2575 3300);
FORCEPROP 1 LAST PATH I165
J 2
(2902 3425);
DISPLAY 0.872340 (2902 3425);
PAINT GREEN (2902 3425);
DISPLAY INVISIBLE (2902 3425);
FORCEADD TAP..1
R 2
(2900 3625);
FORCEPROP 3 LASTPIN (2950 3625) SIG_NAME P5E_CPU1_P2_TX_DN<15>
J 0
(2960 3635);
DISPLAY 0.659574 (2960 3635);
PAINT MONO (2960 3635);
DISPLAY INVISIBLE (2960 3635);
FORCEPROP 1 LASTPIN (2950 3625) BN 15
J 2
(2962 3633);
DISPLAY 0.680851 (2962 3633);
PAINT GREEN (2962 3633);
FORCEPROP 2 LAST CDS_LIB standard
J 0
(2900 3625);
DISPLAY INVISIBLE (2900 3625);
FORCEPROP 1 LAST BODY_TYPE PLUMBING
J 2
(2900 3675);
DISPLAY 0.872340 (2900 3675);
PAINT GREEN (2900 3675);
DISPLAY INVISIBLE (2900 3675);
FORCEPROP 1 LAST HDL_TAP TRUE
J 2
(2575 3500);
DISPLAY 0.872340 (2575 3500);
DISPLAY INVISIBLE (2575 3500);
FORCEPROP 1 LAST PATH I166
J 2
(2902 3625);
DISPLAY 0.872340 (2902 3625);
PAINT GREEN (2902 3625);
DISPLAY INVISIBLE (2902 3625);
FORCEADD Q_CAP_DIFFBUS..2
R 2
(3625 3175);
FORCEPROP 1 LAST LOCATION C747
J 2
(3859 3192);
DISPLAY 0.723404 (3859 3192);
PAINT GREEN (3859 3192);
FORCEPROP 2 LAST $SEC 1
J 2
(3800 3250);
DISPLAY 0.680851 (3800 3250);
PAINT MONO (3800 3250);
DISPLAY INVISIBLE (3800 3250);
FORCEPROP 2 LAST CDS_SEC 1
J 2
(3800 3250);
DISPLAY 0.680851 (3800 3250);
DISPLAY INVISIBLE (3800 3250);
FORCEPROP 2 LASTPIN (3700 3175) $PN 1
J 0
(3710 3185);
DISPLAY 0.808511 (3710 3185);
FORCEPROP 2 LASTPIN (3550 3175) $PN 2
J 2
(3540 3185);
DISPLAY 0.808511 (3540 3185);
FORCEPROP 2 LAST VALUE DIFF BUS_0.22UF
J 2
(3475 3175);
DISPLAY 0.553191 (3475 3175);
FORCEPROP 1 LAST CDS_LMAN_SYM_OUTLINE -25,50,25,-50
J 2
(3625 3175);
DISPLAY 0.468085 (3625 3175);
PAINT GREEN (3625 3175);
DISPLAY INVISIBLE (3625 3175);
FORCEPROP 2 LAST CDS_LIB pure_quanta
J 2
(3625 3175);
DISPLAY INVISIBLE (3625 3175);
FORCEPROP 1 LAST PIN_NAMES_ROTATE TRUE
J 2
(3625 3175);
DISPLAY 0.489362 (3625 3175);
PAINT GREEN (3625 3175);
DISPLAY INVISIBLE (3625 3175);
FORCEPROP 2 LAST VOLTAGE 6.3V
J 2
(3275 3225);
DISPLAY 0.553191 (3275 3225);
DISPLAY INVISIBLE (3275 3225);
FORCEPROP 1 LAST MATERIAL X6S
J 2
(3634 3254);
DISPLAY 0.574468 (3634 3254);
PAINT GREEN (3634 3254);
DISPLAY INVISIBLE (3634 3254);
FORCEPROP 2 LAST PACK_TYPE C0201
J 2
(3450 3225);
DISPLAY 0.553191 (3450 3225);
DISPLAY INVISIBLE (3450 3225);
FORCEPROP 2 LAST TOLERANCE 20%
J 2
(3550 3225);
DISPLAY 0.553191 (3550 3225);
DISPLAY INVISIBLE (3550 3225);
FORCEPROP 1 LAST PART_NUMBER SP_CH4221MEE01
J 2
(3509 3263);
DISPLAY 0.574468 (3509 3263);
PAINT GREEN (3509 3263);
DISPLAY INVISIBLE (3509 3263);
FORCEPROP 1 LAST LOCATION C747
J 0
(3875 3250);
DISPLAY 1.021277 (3875 3250);
DISPLAY INVISIBLE (3875 3250);
FORCEPROP 1 LAST PATH I167
J 2
(3625 3175);
DISPLAY 0.723404 (3625 3175);
DISPLAY INVISIBLE (3625 3175);
FORCEADD Q_CAP_DIFFBUS..2
R 2
(3625 3225);
FORCEPROP 1 LAST LOCATION C746
J 2
(3859 3242);
DISPLAY 0.723404 (3859 3242);
PAINT GREEN (3859 3242);
FORCEPROP 2 LAST $SEC 1
J 2
(3800 3300);
DISPLAY 0.680851 (3800 3300);
PAINT MONO (3800 3300);
DISPLAY INVISIBLE (3800 3300);
FORCEPROP 2 LAST CDS_SEC 1
J 2
(3800 3300);
DISPLAY 0.680851 (3800 3300);
DISPLAY INVISIBLE (3800 3300);
FORCEPROP 2 LASTPIN (3700 3225) $PN 1
J 0
(3710 3235);
DISPLAY 0.808511 (3710 3235);
FORCEPROP 2 LASTPIN (3550 3225) $PN 2
J 2
(3540 3235);
DISPLAY 0.808511 (3540 3235);
FORCEPROP 2 LAST VALUE DIFF BUS_0.22UF
J 2
(3475 3225);
DISPLAY 0.553191 (3475 3225);
FORCEPROP 1 LAST CDS_LMAN_SYM_OUTLINE -25,50,25,-50
J 2
(3625 3225);
DISPLAY 0.468085 (3625 3225);
PAINT GREEN (3625 3225);
DISPLAY INVISIBLE (3625 3225);
FORCEPROP 2 LAST CDS_LIB pure_quanta
J 2
(3625 3225);
DISPLAY INVISIBLE (3625 3225);
FORCEPROP 1 LAST PIN_NAMES_ROTATE TRUE
J 2
(3625 3225);
DISPLAY 0.489362 (3625 3225);
PAINT GREEN (3625 3225);
DISPLAY INVISIBLE (3625 3225);
FORCEPROP 2 LAST VOLTAGE 6.3V
J 2
(3275 3275);
DISPLAY 0.553191 (3275 3275);
DISPLAY INVISIBLE (3275 3275);
FORCEPROP 1 LAST MATERIAL X6S
J 2
(3634 3304);
DISPLAY 0.574468 (3634 3304);
PAINT GREEN (3634 3304);
DISPLAY INVISIBLE (3634 3304);
FORCEPROP 2 LAST PACK_TYPE C0201
J 2
(3450 3275);
DISPLAY 0.553191 (3450 3275);
DISPLAY INVISIBLE (3450 3275);
FORCEPROP 2 LAST TOLERANCE 20%
J 2
(3550 3275);
DISPLAY 0.553191 (3550 3275);
DISPLAY INVISIBLE (3550 3275);
FORCEPROP 1 LAST PART_NUMBER SP_CH4221MEE01
J 2
(3509 3313);
DISPLAY 0.574468 (3509 3313);
PAINT GREEN (3509 3313);
DISPLAY INVISIBLE (3509 3313);
FORCEPROP 1 LAST LOCATION C746
J 0
(3875 3300);
DISPLAY 1.021277 (3875 3300);
DISPLAY INVISIBLE (3875 3300);
FORCEPROP 1 LAST PATH I168
J 2
(3625 3225);
DISPLAY 0.723404 (3625 3225);
DISPLAY INVISIBLE (3625 3225);
FORCEADD Q_CAP_DIFFBUS..2
R 2
(3625 3375);
FORCEPROP 1 LAST LOCATION C745
J 2
(3859 3392);
DISPLAY 0.723404 (3859 3392);
PAINT GREEN (3859 3392);
FORCEPROP 2 LAST $SEC 1
J 2
(3800 3450);
DISPLAY 0.680851 (3800 3450);
PAINT MONO (3800 3450);
DISPLAY INVISIBLE (3800 3450);
FORCEPROP 2 LAST CDS_SEC 1
J 2
(3800 3450);
DISPLAY 0.680851 (3800 3450);
DISPLAY INVISIBLE (3800 3450);
FORCEPROP 2 LASTPIN (3700 3375) $PN 1
J 0
(3710 3385);
DISPLAY 0.808511 (3710 3385);
FORCEPROP 2 LASTPIN (3550 3375) $PN 2
J 2
(3540 3385);
DISPLAY 0.808511 (3540 3385);
FORCEPROP 2 LAST VALUE DIFF BUS_0.22UF
J 2
(3475 3375);
DISPLAY 0.553191 (3475 3375);
FORCEPROP 1 LAST CDS_LMAN_SYM_OUTLINE -25,50,25,-50
J 2
(3625 3375);
DISPLAY 0.468085 (3625 3375);
PAINT GREEN (3625 3375);
DISPLAY INVISIBLE (3625 3375);
FORCEPROP 2 LAST CDS_LIB pure_quanta
J 2
(3625 3375);
DISPLAY INVISIBLE (3625 3375);
FORCEPROP 1 LAST PIN_NAMES_ROTATE TRUE
J 2
(3625 3375);
DISPLAY 0.489362 (3625 3375);
PAINT GREEN (3625 3375);
DISPLAY INVISIBLE (3625 3375);
FORCEPROP 2 LAST VOLTAGE 6.3V
J 2
(3275 3425);
DISPLAY 0.553191 (3275 3425);
DISPLAY INVISIBLE (3275 3425);
FORCEPROP 1 LAST MATERIAL X6S
J 2
(3634 3454);
DISPLAY 0.574468 (3634 3454);
PAINT GREEN (3634 3454);
DISPLAY INVISIBLE (3634 3454);
FORCEPROP 2 LAST PACK_TYPE C0201
J 2
(3450 3425);
DISPLAY 0.553191 (3450 3425);
DISPLAY INVISIBLE (3450 3425);
FORCEPROP 2 LAST TOLERANCE 20%
J 2
(3550 3425);
DISPLAY 0.553191 (3550 3425);
DISPLAY INVISIBLE (3550 3425);
FORCEPROP 1 LAST PART_NUMBER SP_CH4221MEE01
J 2
(3509 3463);
DISPLAY 0.574468 (3509 3463);
PAINT GREEN (3509 3463);
DISPLAY INVISIBLE (3509 3463);
FORCEPROP 1 LAST LOCATION C745
J 0
(3875 3450);
DISPLAY 1.021277 (3875 3450);
DISPLAY INVISIBLE (3875 3450);
FORCEPROP 1 LAST PATH I169
J 2
(3625 3375);
DISPLAY 0.723404 (3625 3375);
DISPLAY INVISIBLE (3625 3375);
FORCEADD Q_CAP_DIFFBUS..2
R 2
(3625 3425);
FORCEPROP 1 LAST LOCATION C744
J 2
(3859 3442);
DISPLAY 0.723404 (3859 3442);
PAINT GREEN (3859 3442);
FORCEPROP 2 LAST $SEC 1
J 2
(3800 3500);
DISPLAY 0.680851 (3800 3500);
PAINT MONO (3800 3500);
DISPLAY INVISIBLE (3800 3500);
FORCEPROP 2 LAST CDS_SEC 1
J 2
(3800 3500);
DISPLAY 0.680851 (3800 3500);
DISPLAY INVISIBLE (3800 3500);
FORCEPROP 2 LASTPIN (3700 3425) $PN 1
J 0
(3710 3435);
DISPLAY 0.808511 (3710 3435);
FORCEPROP 2 LASTPIN (3550 3425) $PN 2
J 2
(3540 3435);
DISPLAY 0.808511 (3540 3435);
FORCEPROP 2 LAST VALUE DIFF BUS_0.22UF
J 2
(3475 3425);
DISPLAY 0.553191 (3475 3425);
FORCEPROP 1 LAST CDS_LMAN_SYM_OUTLINE -25,50,25,-50
J 2
(3625 3425);
DISPLAY 0.468085 (3625 3425);
PAINT GREEN (3625 3425);
DISPLAY INVISIBLE (3625 3425);
FORCEPROP 2 LAST CDS_LIB pure_quanta
J 2
(3625 3425);
DISPLAY INVISIBLE (3625 3425);
FORCEPROP 1 LAST PIN_NAMES_ROTATE TRUE
J 2
(3625 3425);
DISPLAY 0.489362 (3625 3425);
PAINT GREEN (3625 3425);
DISPLAY INVISIBLE (3625 3425);
FORCEPROP 2 LAST VOLTAGE 6.3V
J 2
(3275 3475);
DISPLAY 0.553191 (3275 3475);
DISPLAY INVISIBLE (3275 3475);
FORCEPROP 1 LAST MATERIAL X6S
J 2
(3634 3504);
DISPLAY 0.574468 (3634 3504);
PAINT GREEN (3634 3504);
DISPLAY INVISIBLE (3634 3504);
FORCEPROP 2 LAST PACK_TYPE C0201
J 2
(3450 3475);
DISPLAY 0.553191 (3450 3475);
DISPLAY INVISIBLE (3450 3475);
FORCEPROP 2 LAST TOLERANCE 20%
J 2
(3550 3475);
DISPLAY 0.553191 (3550 3475);
DISPLAY INVISIBLE (3550 3475);
FORCEPROP 1 LAST PART_NUMBER SP_CH4221MEE01
J 2
(3509 3513);
DISPLAY 0.574468 (3509 3513);
PAINT GREEN (3509 3513);
DISPLAY INVISIBLE (3509 3513);
FORCEPROP 1 LAST LOCATION C744
J 0
(3875 3500);
DISPLAY 1.021277 (3875 3500);
DISPLAY INVISIBLE (3875 3500);
FORCEPROP 1 LAST PATH I170
J 2
(3625 3425);
DISPLAY 0.723404 (3625 3425);
DISPLAY INVISIBLE (3625 3425);
FORCEADD Q_CAP_DIFFBUS..2
R 2
(3625 3575);
FORCEPROP 1 LAST LOCATION C743
J 2
(3859 3592);
DISPLAY 0.723404 (3859 3592);
PAINT GREEN (3859 3592);
FORCEPROP 2 LAST $SEC 1
J 2
(3800 3650);
DISPLAY 0.680851 (3800 3650);
PAINT MONO (3800 3650);
DISPLAY INVISIBLE (3800 3650);
FORCEPROP 2 LAST CDS_SEC 1
J 2
(3800 3650);
DISPLAY 0.680851 (3800 3650);
DISPLAY INVISIBLE (3800 3650);
FORCEPROP 2 LASTPIN (3700 3575) $PN 1
J 0
(3710 3585);
DISPLAY 0.808511 (3710 3585);
FORCEPROP 2 LASTPIN (3550 3575) $PN 2
J 2
(3540 3585);
DISPLAY 0.808511 (3540 3585);
FORCEPROP 2 LAST VALUE DIFF BUS_0.22UF
J 2
(3475 3575);
DISPLAY 0.553191 (3475 3575);
FORCEPROP 1 LAST CDS_LMAN_SYM_OUTLINE -25,50,25,-50
J 2
(3625 3575);
DISPLAY 0.468085 (3625 3575);
PAINT GREEN (3625 3575);
DISPLAY INVISIBLE (3625 3575);
FORCEPROP 2 LAST CDS_LIB pure_quanta
J 2
(3625 3575);
DISPLAY INVISIBLE (3625 3575);
FORCEPROP 1 LAST PIN_NAMES_ROTATE TRUE
J 2
(3625 3575);
DISPLAY 0.489362 (3625 3575);
PAINT GREEN (3625 3575);
DISPLAY INVISIBLE (3625 3575);
FORCEPROP 2 LAST VOLTAGE 6.3V
J 2
(3275 3625);
DISPLAY 0.553191 (3275 3625);
DISPLAY INVISIBLE (3275 3625);
FORCEPROP 1 LAST MATERIAL X6S
J 2
(3634 3654);
DISPLAY 0.574468 (3634 3654);
PAINT GREEN (3634 3654);
DISPLAY INVISIBLE (3634 3654);
FORCEPROP 2 LAST PACK_TYPE C0201
J 2
(3450 3625);
DISPLAY 0.553191 (3450 3625);
DISPLAY INVISIBLE (3450 3625);
FORCEPROP 2 LAST TOLERANCE 20%
J 2
(3550 3625);
DISPLAY 0.553191 (3550 3625);
DISPLAY INVISIBLE (3550 3625);
FORCEPROP 1 LAST PART_NUMBER SP_CH4221MEE01
J 2
(3509 3663);
DISPLAY 0.574468 (3509 3663);
PAINT GREEN (3509 3663);
DISPLAY INVISIBLE (3509 3663);
FORCEPROP 1 LAST LOCATION C743
J 0
(3875 3650);
DISPLAY 1.021277 (3875 3650);
DISPLAY INVISIBLE (3875 3650);
FORCEPROP 1 LAST PATH I171
J 2
(3625 3575);
DISPLAY 0.723404 (3625 3575);
DISPLAY INVISIBLE (3625 3575);
FORCEADD Q_CAP_DIFFBUS..2
R 2
(3625 3625);
FORCEPROP 1 LAST LOCATION C742
J 2
(3859 3642);
DISPLAY 0.723404 (3859 3642);
PAINT GREEN (3859 3642);
FORCEPROP 2 LAST $SEC 1
J 2
(3800 3700);
DISPLAY 0.680851 (3800 3700);
PAINT MONO (3800 3700);
DISPLAY INVISIBLE (3800 3700);
FORCEPROP 2 LAST CDS_SEC 1
J 2
(3800 3700);
DISPLAY 0.680851 (3800 3700);
DISPLAY INVISIBLE (3800 3700);
FORCEPROP 2 LASTPIN (3700 3625) $PN 1
J 0
(3710 3635);
DISPLAY 0.808511 (3710 3635);
FORCEPROP 2 LASTPIN (3550 3625) $PN 2
J 2
(3540 3635);
DISPLAY 0.808511 (3540 3635);
FORCEPROP 2 LAST VOLTAGE 6.3V
J 2
(3875 3775);
DISPLAY 0.553191 (3875 3775);
PAINT GREEN (3875 3775);
FORCEPROP 2 LAST TOLERANCE 20%
J 2
(3725 3775);
DISPLAY 0.553191 (3725 3775);
PAINT GREEN (3725 3775);
FORCEPROP 1 LAST MATERIAL X6S
J 2
(3584 3829);
DISPLAY 0.574468 (3584 3829);
PAINT GREEN (3584 3829);
FORCEPROP 2 LAST PACK_TYPE C0201
J 2
(3625 3775);
DISPLAY 0.553191 (3625 3775);
PAINT GREEN (3625 3775);
FORCEPROP 2 LAST VALUE DIFF BUS_0.22UF
J 2
(3475 3625);
DISPLAY 0.553191 (3475 3625);
FORCEPROP 2 LAST CDS_LIB pure_quanta
J 2
(3625 3625);
DISPLAY INVISIBLE (3625 3625);
FORCEPROP 1 LAST CDS_LMAN_SYM_OUTLINE -25,50,25,-50
J 2
(3625 3625);
DISPLAY 0.468085 (3625 3625);
PAINT GREEN (3625 3625);
DISPLAY INVISIBLE (3625 3625);
FORCEPROP 1 LAST PIN_NAMES_ROTATE TRUE
J 2
(3625 3625);
DISPLAY 0.489362 (3625 3625);
PAINT GREEN (3625 3625);
DISPLAY INVISIBLE (3625 3625);
FORCEPROP 1 LAST PART_NUMBER SP_CH4221MEE01
J 2
(3884 3713);
DISPLAY 0.574468 (3884 3713);
PAINT GREEN (3884 3713);
DISPLAY INVISIBLE (3884 3713);
FORCEPROP 1 LAST LOCATION C742
J 0
(3875 3700);
DISPLAY 1.021277 (3875 3700);
DISPLAY INVISIBLE (3875 3700);
FORCEPROP 1 LAST PATH I172
J 2
(3625 3625);
DISPLAY 0.723404 (3625 3625);
DISPLAY INVISIBLE (3625 3625);
FORCEADD TAP..1
(4175 250);
FORCEPROP 3 LASTPIN (4125 250) SIG_NAME P5E_CPU1_P2_TX_C_DN<0>
J 0
(4135 260);
DISPLAY 0.659574 (4135 260);
PAINT MONO (4135 260);
DISPLAY INVISIBLE (4135 260);
FORCEPROP 1 LASTPIN (4125 250) BN 0
J 0
(4113 258);
DISPLAY 0.680851 (4113 258);
PAINT GREEN (4113 258);
FORCEPROP 2 LAST CDS_LIB standard
J 0
(4175 250);
DISPLAY INVISIBLE (4175 250);
FORCEPROP 1 LAST BODY_TYPE PLUMBING
J 0
(4175 300);
DISPLAY 0.872340 (4175 300);
PAINT GREEN (4175 300);
DISPLAY INVISIBLE (4175 300);
FORCEPROP 1 LAST HDL_TAP TRUE
J 0
(4500 125);
DISPLAY 0.872340 (4500 125);
DISPLAY INVISIBLE (4500 125);
FORCEPROP 1 LAST PATH I173
J 0
(4173 250);
DISPLAY 0.872340 (4173 250);
PAINT GREEN (4173 250);
DISPLAY INVISIBLE (4173 250);
FORCEADD TAP..1
(4175 450);
FORCEPROP 3 LASTPIN (4125 450) SIG_NAME P5E_CPU1_P2_TX_C_DN<1>
J 0
(4135 460);
DISPLAY 0.659574 (4135 460);
PAINT MONO (4135 460);
DISPLAY INVISIBLE (4135 460);
FORCEPROP 1 LASTPIN (4125 450) BN 1
J 0
(4113 458);
DISPLAY 0.680851 (4113 458);
PAINT GREEN (4113 458);
FORCEPROP 2 LAST CDS_LIB standard
J 0
(4175 450);
DISPLAY INVISIBLE (4175 450);
FORCEPROP 1 LAST BODY_TYPE PLUMBING
J 0
(4175 500);
DISPLAY 0.872340 (4175 500);
PAINT GREEN (4175 500);
DISPLAY INVISIBLE (4175 500);
FORCEPROP 1 LAST HDL_TAP TRUE
J 0
(4500 325);
DISPLAY 0.872340 (4500 325);
DISPLAY INVISIBLE (4500 325);
FORCEPROP 1 LAST PATH I174
J 0
(4173 450);
DISPLAY 0.872340 (4173 450);
PAINT GREEN (4173 450);
DISPLAY INVISIBLE (4173 450);
FORCEADD TAP..1
(4175 650);
FORCEPROP 3 LASTPIN (4125 650) SIG_NAME P5E_CPU1_P2_TX_C_DN<2>
J 0
(4135 660);
DISPLAY 0.659574 (4135 660);
PAINT MONO (4135 660);
DISPLAY INVISIBLE (4135 660);
FORCEPROP 1 LASTPIN (4125 650) BN 2
J 0
(4113 658);
DISPLAY 0.680851 (4113 658);
PAINT GREEN (4113 658);
FORCEPROP 2 LAST CDS_LIB standard
J 0
(4175 650);
DISPLAY INVISIBLE (4175 650);
FORCEPROP 1 LAST BODY_TYPE PLUMBING
J 0
(4175 700);
DISPLAY 0.872340 (4175 700);
PAINT GREEN (4175 700);
DISPLAY INVISIBLE (4175 700);
FORCEPROP 1 LAST HDL_TAP TRUE
J 0
(4500 525);
DISPLAY 0.872340 (4500 525);
DISPLAY INVISIBLE (4500 525);
FORCEPROP 1 LAST PATH I175
J 0
(4173 650);
DISPLAY 0.872340 (4173 650);
PAINT GREEN (4173 650);
DISPLAY INVISIBLE (4173 650);
FORCEADD TAP..1
(4175 1050);
FORCEPROP 3 LASTPIN (4125 1050) SIG_NAME P5E_CPU1_P2_TX_C_DN<4>
J 0
(4135 1060);
DISPLAY 0.659574 (4135 1060);
PAINT MONO (4135 1060);
DISPLAY INVISIBLE (4135 1060);
FORCEPROP 1 LASTPIN (4125 1050) BN 4
J 0
(4113 1058);
DISPLAY 0.680851 (4113 1058);
PAINT GREEN (4113 1058);
FORCEPROP 2 LAST CDS_LIB standard
J 0
(4175 1050);
DISPLAY INVISIBLE (4175 1050);
FORCEPROP 1 LAST BODY_TYPE PLUMBING
J 0
(4175 1100);
DISPLAY 0.872340 (4175 1100);
PAINT GREEN (4175 1100);
DISPLAY INVISIBLE (4175 1100);
FORCEPROP 1 LAST HDL_TAP TRUE
J 0
(4500 925);
DISPLAY 0.872340 (4500 925);
DISPLAY INVISIBLE (4500 925);
FORCEPROP 1 LAST PATH I176
J 0
(4173 1050);
DISPLAY 0.872340 (4173 1050);
PAINT GREEN (4173 1050);
DISPLAY INVISIBLE (4173 1050);
FORCEADD TAP..1
(4175 850);
FORCEPROP 3 LASTPIN (4125 850) SIG_NAME P5E_CPU1_P2_TX_C_DN<3>
J 0
(4135 860);
DISPLAY 0.659574 (4135 860);
PAINT MONO (4135 860);
DISPLAY INVISIBLE (4135 860);
FORCEPROP 1 LASTPIN (4125 850) BN 3
J 0
(4113 858);
DISPLAY 0.680851 (4113 858);
PAINT GREEN (4113 858);
FORCEPROP 2 LAST CDS_LIB standard
J 0
(4175 850);
DISPLAY INVISIBLE (4175 850);
FORCEPROP 1 LAST BODY_TYPE PLUMBING
J 0
(4175 900);
DISPLAY 0.872340 (4175 900);
PAINT GREEN (4175 900);
DISPLAY INVISIBLE (4175 900);
FORCEPROP 1 LAST HDL_TAP TRUE
J 0
(4500 725);
DISPLAY 0.872340 (4500 725);
DISPLAY INVISIBLE (4500 725);
FORCEPROP 1 LAST PATH I177
J 0
(4173 850);
DISPLAY 0.872340 (4173 850);
PAINT GREEN (4173 850);
DISPLAY INVISIBLE (4173 850);
FORCEADD TAP..1
(4375 200);
FORCEPROP 3 LASTPIN (4325 200) SIG_NAME P5E_CPU1_P2_TX_C_DP<0>
J 0
(4335 210);
DISPLAY 0.659574 (4335 210);
PAINT MONO (4335 210);
DISPLAY INVISIBLE (4335 210);
FORCEPROP 1 LASTPIN (4325 200) BN 0
J 0
(4313 208);
DISPLAY 0.680851 (4313 208);
PAINT GREEN (4313 208);
FORCEPROP 2 LAST CDS_LIB standard
J 0
(4375 200);
DISPLAY INVISIBLE (4375 200);
FORCEPROP 1 LAST BODY_TYPE PLUMBING
J 0
(4375 250);
DISPLAY 0.872340 (4375 250);
PAINT GREEN (4375 250);
DISPLAY INVISIBLE (4375 250);
FORCEPROP 1 LAST HDL_TAP TRUE
J 0
(4700 75);
DISPLAY 0.872340 (4700 75);
DISPLAY INVISIBLE (4700 75);
FORCEPROP 1 LAST PATH I178
J 0
(4373 200);
DISPLAY 0.872340 (4373 200);
PAINT GREEN (4373 200);
DISPLAY INVISIBLE (4373 200);
FORCEADD TAP..1
(4375 400);
FORCEPROP 3 LASTPIN (4325 400) SIG_NAME P5E_CPU1_P2_TX_C_DP<1>
J 0
(4335 410);
DISPLAY 0.659574 (4335 410);
PAINT MONO (4335 410);
DISPLAY INVISIBLE (4335 410);
FORCEPROP 1 LASTPIN (4325 400) BN 1
J 0
(4313 408);
DISPLAY 0.680851 (4313 408);
PAINT GREEN (4313 408);
FORCEPROP 2 LAST CDS_LIB standard
J 0
(4375 400);
DISPLAY INVISIBLE (4375 400);
FORCEPROP 1 LAST BODY_TYPE PLUMBING
J 0
(4375 450);
DISPLAY 0.872340 (4375 450);
PAINT GREEN (4375 450);
DISPLAY INVISIBLE (4375 450);
FORCEPROP 1 LAST HDL_TAP TRUE
J 0
(4700 275);
DISPLAY 0.872340 (4700 275);
DISPLAY INVISIBLE (4700 275);
FORCEPROP 1 LAST PATH I179
J 0
(4373 400);
DISPLAY 0.872340 (4373 400);
PAINT GREEN (4373 400);
DISPLAY INVISIBLE (4373 400);
FORCEADD TAP..1
(4375 600);
FORCEPROP 3 LASTPIN (4325 600) SIG_NAME P5E_CPU1_P2_TX_C_DP<2>
J 0
(4335 610);
DISPLAY 0.659574 (4335 610);
PAINT MONO (4335 610);
DISPLAY INVISIBLE (4335 610);
FORCEPROP 1 LASTPIN (4325 600) BN 2
J 0
(4313 608);
DISPLAY 0.680851 (4313 608);
PAINT GREEN (4313 608);
FORCEPROP 2 LAST CDS_LIB standard
J 0
(4375 600);
DISPLAY INVISIBLE (4375 600);
FORCEPROP 1 LAST BODY_TYPE PLUMBING
J 0
(4375 650);
DISPLAY 0.872340 (4375 650);
PAINT GREEN (4375 650);
DISPLAY INVISIBLE (4375 650);
FORCEPROP 1 LAST HDL_TAP TRUE
J 0
(4700 475);
DISPLAY 0.872340 (4700 475);
DISPLAY INVISIBLE (4700 475);
FORCEPROP 1 LAST PATH I180
J 0
(4373 600);
DISPLAY 0.872340 (4373 600);
PAINT GREEN (4373 600);
DISPLAY INVISIBLE (4373 600);
FORCEADD TAP..1
(4375 800);
FORCEPROP 3 LASTPIN (4325 800) SIG_NAME P5E_CPU1_P2_TX_C_DP<3>
J 0
(4335 810);
DISPLAY 0.659574 (4335 810);
PAINT MONO (4335 810);
DISPLAY INVISIBLE (4335 810);
FORCEPROP 1 LASTPIN (4325 800) BN 3
J 0
(4313 808);
DISPLAY 0.680851 (4313 808);
PAINT GREEN (4313 808);
FORCEPROP 2 LAST CDS_LIB standard
J 0
(4375 800);
DISPLAY INVISIBLE (4375 800);
FORCEPROP 1 LAST BODY_TYPE PLUMBING
J 0
(4375 850);
DISPLAY 0.872340 (4375 850);
PAINT GREEN (4375 850);
DISPLAY INVISIBLE (4375 850);
FORCEPROP 1 LAST HDL_TAP TRUE
J 0
(4700 675);
DISPLAY 0.872340 (4700 675);
DISPLAY INVISIBLE (4700 675);
FORCEPROP 1 LAST PATH I181
J 0
(4373 800);
DISPLAY 0.872340 (4373 800);
PAINT GREEN (4373 800);
DISPLAY INVISIBLE (4373 800);
FORCEADD TAP..1
(4375 1000);
FORCEPROP 3 LASTPIN (4325 1000) SIG_NAME P5E_CPU1_P2_TX_C_DP<4>
J 0
(4335 1010);
DISPLAY 0.659574 (4335 1010);
PAINT MONO (4335 1010);
DISPLAY INVISIBLE (4335 1010);
FORCEPROP 1 LASTPIN (4325 1000) BN 4
J 0
(4313 1008);
DISPLAY 0.680851 (4313 1008);
PAINT GREEN (4313 1008);
FORCEPROP 2 LAST CDS_LIB standard
J 0
(4375 1000);
DISPLAY INVISIBLE (4375 1000);
FORCEPROP 1 LAST BODY_TYPE PLUMBING
J 0
(4375 1050);
DISPLAY 0.872340 (4375 1050);
PAINT GREEN (4375 1050);
DISPLAY INVISIBLE (4375 1050);
FORCEPROP 1 LAST HDL_TAP TRUE
J 0
(4700 875);
DISPLAY 0.872340 (4700 875);
DISPLAY INVISIBLE (4700 875);
FORCEPROP 1 LAST PATH I182
J 0
(4373 1000);
DISPLAY 0.872340 (4373 1000);
PAINT GREEN (4373 1000);
DISPLAY INVISIBLE (4373 1000);
FORCEADD TAP..1
(4175 1250);
FORCEPROP 3 LASTPIN (4125 1250) SIG_NAME P5E_CPU1_P2_TX_C_DN<5>
J 0
(4135 1260);
DISPLAY 0.659574 (4135 1260);
PAINT MONO (4135 1260);
DISPLAY INVISIBLE (4135 1260);
FORCEPROP 1 LASTPIN (4125 1250) BN 5
J 0
(4113 1258);
DISPLAY 0.680851 (4113 1258);
PAINT GREEN (4113 1258);
FORCEPROP 2 LAST CDS_LIB standard
J 0
(4175 1250);
DISPLAY INVISIBLE (4175 1250);
FORCEPROP 1 LAST BODY_TYPE PLUMBING
J 0
(4175 1300);
DISPLAY 0.872340 (4175 1300);
PAINT GREEN (4175 1300);
DISPLAY INVISIBLE (4175 1300);
FORCEPROP 1 LAST HDL_TAP TRUE
J 0
(4500 1125);
DISPLAY 0.872340 (4500 1125);
DISPLAY INVISIBLE (4500 1125);
FORCEPROP 1 LAST PATH I183
J 0
(4173 1250);
DISPLAY 0.872340 (4173 1250);
PAINT GREEN (4173 1250);
DISPLAY INVISIBLE (4173 1250);
FORCEADD TAP..1
(4175 1450);
FORCEPROP 3 LASTPIN (4125 1450) SIG_NAME P5E_CPU1_P2_TX_C_DN<6>
J 0
(4135 1460);
DISPLAY 0.659574 (4135 1460);
PAINT MONO (4135 1460);
DISPLAY INVISIBLE (4135 1460);
FORCEPROP 1 LASTPIN (4125 1450) BN 6
J 0
(4113 1458);
DISPLAY 0.680851 (4113 1458);
PAINT GREEN (4113 1458);
FORCEPROP 2 LAST CDS_LIB standard
J 0
(4175 1450);
DISPLAY INVISIBLE (4175 1450);
FORCEPROP 1 LAST BODY_TYPE PLUMBING
J 0
(4175 1500);
DISPLAY 0.872340 (4175 1500);
PAINT GREEN (4175 1500);
DISPLAY INVISIBLE (4175 1500);
FORCEPROP 1 LAST HDL_TAP TRUE
J 0
(4500 1325);
DISPLAY 0.872340 (4500 1325);
DISPLAY INVISIBLE (4500 1325);
FORCEPROP 1 LAST PATH I184
J 0
(4173 1450);
DISPLAY 0.872340 (4173 1450);
PAINT GREEN (4173 1450);
DISPLAY INVISIBLE (4173 1450);
FORCEADD TAP..1
(4175 1650);
FORCEPROP 3 LASTPIN (4125 1650) SIG_NAME P5E_CPU1_P2_TX_C_DN<7>
J 0
(4135 1660);
DISPLAY 0.659574 (4135 1660);
PAINT MONO (4135 1660);
DISPLAY INVISIBLE (4135 1660);
FORCEPROP 1 LASTPIN (4125 1650) BN 7
J 0
(4113 1658);
DISPLAY 0.680851 (4113 1658);
PAINT GREEN (4113 1658);
FORCEPROP 2 LAST CDS_LIB standard
J 0
(4175 1650);
DISPLAY INVISIBLE (4175 1650);
FORCEPROP 1 LAST BODY_TYPE PLUMBING
J 0
(4175 1700);
DISPLAY 0.872340 (4175 1700);
PAINT GREEN (4175 1700);
DISPLAY INVISIBLE (4175 1700);
FORCEPROP 1 LAST HDL_TAP TRUE
J 0
(4500 1525);
DISPLAY 0.872340 (4500 1525);
DISPLAY INVISIBLE (4500 1525);
FORCEPROP 1 LAST PATH I185
J 0
(4173 1650);
DISPLAY 0.872340 (4173 1650);
PAINT GREEN (4173 1650);
DISPLAY INVISIBLE (4173 1650);
FORCEADD TAP..1
(4375 1200);
FORCEPROP 3 LASTPIN (4325 1200) SIG_NAME P5E_CPU1_P2_TX_C_DP<5>
J 0
(4335 1210);
DISPLAY 0.659574 (4335 1210);
PAINT MONO (4335 1210);
DISPLAY INVISIBLE (4335 1210);
FORCEPROP 1 LASTPIN (4325 1200) BN 5
J 0
(4313 1208);
DISPLAY 0.680851 (4313 1208);
PAINT GREEN (4313 1208);
FORCEPROP 2 LAST CDS_LIB standard
J 0
(4375 1200);
DISPLAY INVISIBLE (4375 1200);
FORCEPROP 1 LAST BODY_TYPE PLUMBING
J 0
(4375 1250);
DISPLAY 0.872340 (4375 1250);
PAINT GREEN (4375 1250);
DISPLAY INVISIBLE (4375 1250);
FORCEPROP 1 LAST HDL_TAP TRUE
J 0
(4700 1075);
DISPLAY 0.872340 (4700 1075);
DISPLAY INVISIBLE (4700 1075);
FORCEPROP 1 LAST PATH I186
J 0
(4373 1200);
DISPLAY 0.872340 (4373 1200);
PAINT GREEN (4373 1200);
DISPLAY INVISIBLE (4373 1200);
FORCEADD TAP..1
(4375 1400);
FORCEPROP 3 LASTPIN (4325 1400) SIG_NAME P5E_CPU1_P2_TX_C_DP<6>
J 0
(4335 1410);
DISPLAY 0.659574 (4335 1410);
PAINT MONO (4335 1410);
DISPLAY INVISIBLE (4335 1410);
FORCEPROP 1 LASTPIN (4325 1400) BN 6
J 0
(4313 1408);
DISPLAY 0.680851 (4313 1408);
PAINT GREEN (4313 1408);
FORCEPROP 2 LAST CDS_LIB standard
J 0
(4375 1400);
DISPLAY INVISIBLE (4375 1400);
FORCEPROP 1 LAST BODY_TYPE PLUMBING
J 0
(4375 1450);
DISPLAY 0.872340 (4375 1450);
PAINT GREEN (4375 1450);
DISPLAY INVISIBLE (4375 1450);
FORCEPROP 1 LAST HDL_TAP TRUE
J 0
(4700 1275);
DISPLAY 0.872340 (4700 1275);
DISPLAY INVISIBLE (4700 1275);
FORCEPROP 1 LAST PATH I187
J 0
(4373 1400);
DISPLAY 0.872340 (4373 1400);
PAINT GREEN (4373 1400);
DISPLAY INVISIBLE (4373 1400);
FORCEADD TAP..1
(4375 1600);
FORCEPROP 3 LASTPIN (4325 1600) SIG_NAME P5E_CPU1_P2_TX_C_DP<7>
J 0
(4335 1610);
DISPLAY 0.659574 (4335 1610);
PAINT MONO (4335 1610);
DISPLAY INVISIBLE (4335 1610);
FORCEPROP 1 LASTPIN (4325 1600) BN 7
J 0
(4313 1608);
DISPLAY 0.680851 (4313 1608);
PAINT GREEN (4313 1608);
FORCEPROP 2 LAST CDS_LIB standard
J 0
(4375 1600);
DISPLAY INVISIBLE (4375 1600);
FORCEPROP 1 LAST BODY_TYPE PLUMBING
J 0
(4375 1650);
DISPLAY 0.872340 (4375 1650);
PAINT GREEN (4375 1650);
DISPLAY INVISIBLE (4375 1650);
FORCEPROP 1 LAST HDL_TAP TRUE
J 0
(4700 1475);
DISPLAY 0.872340 (4700 1475);
DISPLAY INVISIBLE (4700 1475);
FORCEPROP 1 LAST PATH I188
J 0
(4373 1600);
DISPLAY 0.872340 (4373 1600);
PAINT GREEN (4373 1600);
DISPLAY INVISIBLE (4373 1600);
FORCEADD OFFPAGE..2
(5375 1625);
FORCEPROP 2 LAST $XR0 339 
J 0
(5564 1625);
DISPLAY 0.638298 (5564 1625);
PAINT MONO (5564 1625);
FORCEPROP 2 LAST CDS_LIB standard
J 0
(5375 1625);
DISPLAY INVISIBLE (5375 1625);
FORCEPROP 1 LAST OFFPAGE TRUE
J 0
(5700 1500);
DISPLAY 0.872340 (5700 1500);
DISPLAY INVISIBLE (5700 1500);
FORCEPROP 1 LAST COMMENT_BODY TRUE
J 0
(5330 1530);
DISPLAY 0.872340 (5330 1530);
PAINT GREEN (5330 1530);
DISPLAY INVISIBLE (5330 1530);
FORCEPROP 2 LAST PATH I189
J 0
(5550 1700);
DISPLAY 1.021277 (5550 1700);
DISPLAY INVISIBLE (5550 1700);
FORCEADD OFFPAGE..2
(5375 1675);
FORCEPROP 2 LAST $XR0 339 
J 0
(5564 1675);
DISPLAY 0.638298 (5564 1675);
PAINT MONO (5564 1675);
FORCEPROP 2 LAST CDS_LIB standard
J 0
(5375 1675);
DISPLAY INVISIBLE (5375 1675);
FORCEPROP 1 LAST OFFPAGE TRUE
J 0
(5700 1550);
DISPLAY 0.872340 (5700 1550);
DISPLAY INVISIBLE (5700 1550);
FORCEPROP 1 LAST COMMENT_BODY TRUE
J 0
(5330 1580);
DISPLAY 0.872340 (5330 1580);
PAINT GREEN (5330 1580);
DISPLAY INVISIBLE (5330 1580);
FORCEPROP 2 LAST PATH I190
J 0
(5550 1750);
DISPLAY 1.021277 (5550 1750);
DISPLAY INVISIBLE (5550 1750);
FORCEADD TAP..1
(4175 2225);
FORCEPROP 3 LASTPIN (4125 2225) SIG_NAME P5E_CPU1_P2_TX_C_DN<8>
J 0
(4135 2235);
DISPLAY 0.659574 (4135 2235);
PAINT MONO (4135 2235);
DISPLAY INVISIBLE (4135 2235);
FORCEPROP 1 LASTPIN (4125 2225) BN 8
J 0
(4113 2233);
DISPLAY 0.680851 (4113 2233);
PAINT GREEN (4113 2233);
FORCEPROP 2 LAST CDS_LIB standard
J 0
(4175 2225);
DISPLAY INVISIBLE (4175 2225);
FORCEPROP 1 LAST BODY_TYPE PLUMBING
J 0
(4175 2275);
DISPLAY 0.872340 (4175 2275);
PAINT GREEN (4175 2275);
DISPLAY INVISIBLE (4175 2275);
FORCEPROP 1 LAST HDL_TAP TRUE
J 0
(4500 2100);
DISPLAY 0.872340 (4500 2100);
DISPLAY INVISIBLE (4500 2100);
FORCEPROP 1 LAST PATH I191
J 0
(4173 2225);
DISPLAY 0.872340 (4173 2225);
PAINT GREEN (4173 2225);
DISPLAY INVISIBLE (4173 2225);
FORCEADD TAP..1
(4175 2425);
FORCEPROP 3 LASTPIN (4125 2425) SIG_NAME P5E_CPU1_P2_TX_C_DN<9>
J 0
(4135 2435);
DISPLAY 0.659574 (4135 2435);
PAINT MONO (4135 2435);
DISPLAY INVISIBLE (4135 2435);
FORCEPROP 1 LASTPIN (4125 2425) BN 9
J 0
(4113 2433);
DISPLAY 0.680851 (4113 2433);
PAINT GREEN (4113 2433);
FORCEPROP 2 LAST CDS_LIB standard
J 0
(4175 2425);
DISPLAY INVISIBLE (4175 2425);
FORCEPROP 1 LAST BODY_TYPE PLUMBING
J 0
(4175 2475);
DISPLAY 0.872340 (4175 2475);
PAINT GREEN (4175 2475);
DISPLAY INVISIBLE (4175 2475);
FORCEPROP 1 LAST HDL_TAP TRUE
J 0
(4500 2300);
DISPLAY 0.872340 (4500 2300);
DISPLAY INVISIBLE (4500 2300);
FORCEPROP 1 LAST PATH I192
J 0
(4173 2425);
DISPLAY 0.872340 (4173 2425);
PAINT GREEN (4173 2425);
DISPLAY INVISIBLE (4173 2425);
FORCEADD TAP..1
(4175 2625);
FORCEPROP 3 LASTPIN (4125 2625) SIG_NAME P5E_CPU1_P2_TX_C_DN<10>
J 0
(4135 2635);
DISPLAY 0.659574 (4135 2635);
PAINT MONO (4135 2635);
DISPLAY INVISIBLE (4135 2635);
FORCEPROP 1 LASTPIN (4125 2625) BN 10
J 0
(4113 2633);
DISPLAY 0.680851 (4113 2633);
PAINT GREEN (4113 2633);
FORCEPROP 2 LAST CDS_LIB standard
J 0
(4175 2625);
DISPLAY INVISIBLE (4175 2625);
FORCEPROP 1 LAST BODY_TYPE PLUMBING
J 0
(4175 2675);
DISPLAY 0.872340 (4175 2675);
PAINT GREEN (4175 2675);
DISPLAY INVISIBLE (4175 2675);
FORCEPROP 1 LAST HDL_TAP TRUE
J 0
(4500 2500);
DISPLAY 0.872340 (4500 2500);
DISPLAY INVISIBLE (4500 2500);
FORCEPROP 1 LAST PATH I193
J 0
(4173 2625);
DISPLAY 0.872340 (4173 2625);
PAINT GREEN (4173 2625);
DISPLAY INVISIBLE (4173 2625);
FORCEADD TAP..1
(4175 2825);
FORCEPROP 3 LASTPIN (4125 2825) SIG_NAME P5E_CPU1_P2_TX_C_DN<11>
J 0
(4135 2835);
DISPLAY 0.659574 (4135 2835);
PAINT MONO (4135 2835);
DISPLAY INVISIBLE (4135 2835);
FORCEPROP 1 LASTPIN (4125 2825) BN 11
J 0
(4113 2833);
DISPLAY 0.680851 (4113 2833);
PAINT GREEN (4113 2833);
FORCEPROP 2 LAST CDS_LIB standard
J 0
(4175 2825);
DISPLAY INVISIBLE (4175 2825);
FORCEPROP 1 LAST BODY_TYPE PLUMBING
J 0
(4175 2875);
DISPLAY 0.872340 (4175 2875);
PAINT GREEN (4175 2875);
DISPLAY INVISIBLE (4175 2875);
FORCEPROP 1 LAST HDL_TAP TRUE
J 0
(4500 2700);
DISPLAY 0.872340 (4500 2700);
DISPLAY INVISIBLE (4500 2700);
FORCEPROP 1 LAST PATH I194
J 0
(4173 2825);
DISPLAY 0.872340 (4173 2825);
PAINT GREEN (4173 2825);
DISPLAY INVISIBLE (4173 2825);
FORCEADD TAP..1
(4175 3025);
FORCEPROP 3 LASTPIN (4125 3025) SIG_NAME P5E_CPU1_P2_TX_C_DN<12>
J 0
(4135 3035);
DISPLAY 0.659574 (4135 3035);
PAINT MONO (4135 3035);
DISPLAY INVISIBLE (4135 3035);
FORCEPROP 1 LASTPIN (4125 3025) BN 12
J 0
(4113 3033);
DISPLAY 0.680851 (4113 3033);
PAINT GREEN (4113 3033);
FORCEPROP 2 LAST CDS_LIB standard
J 0
(4175 3025);
DISPLAY INVISIBLE (4175 3025);
FORCEPROP 1 LAST BODY_TYPE PLUMBING
J 0
(4175 3075);
DISPLAY 0.872340 (4175 3075);
PAINT GREEN (4175 3075);
DISPLAY INVISIBLE (4175 3075);
FORCEPROP 1 LAST HDL_TAP TRUE
J 0
(4500 2900);
DISPLAY 0.872340 (4500 2900);
DISPLAY INVISIBLE (4500 2900);
FORCEPROP 1 LAST PATH I195
J 0
(4173 3025);
DISPLAY 0.872340 (4173 3025);
PAINT GREEN (4173 3025);
DISPLAY INVISIBLE (4173 3025);
FORCEADD TAP..1
(4375 2175);
FORCEPROP 3 LASTPIN (4325 2175) SIG_NAME P5E_CPU1_P2_TX_C_DP<8>
J 0
(4335 2185);
DISPLAY 0.659574 (4335 2185);
PAINT MONO (4335 2185);
DISPLAY INVISIBLE (4335 2185);
FORCEPROP 1 LASTPIN (4325 2175) BN 8
J 0
(4313 2183);
DISPLAY 0.680851 (4313 2183);
PAINT GREEN (4313 2183);
FORCEPROP 2 LAST CDS_LIB standard
J 0
(4375 2175);
DISPLAY INVISIBLE (4375 2175);
FORCEPROP 1 LAST BODY_TYPE PLUMBING
J 0
(4375 2225);
DISPLAY 0.872340 (4375 2225);
PAINT GREEN (4375 2225);
DISPLAY INVISIBLE (4375 2225);
FORCEPROP 1 LAST HDL_TAP TRUE
J 0
(4700 2050);
DISPLAY 0.872340 (4700 2050);
DISPLAY INVISIBLE (4700 2050);
FORCEPROP 1 LAST PATH I196
J 0
(4373 2175);
DISPLAY 0.872340 (4373 2175);
PAINT GREEN (4373 2175);
DISPLAY INVISIBLE (4373 2175);
FORCEADD TAP..1
(4375 2375);
FORCEPROP 3 LASTPIN (4325 2375) SIG_NAME P5E_CPU1_P2_TX_C_DP<9>
J 0
(4335 2385);
DISPLAY 0.659574 (4335 2385);
PAINT MONO (4335 2385);
DISPLAY INVISIBLE (4335 2385);
FORCEPROP 1 LASTPIN (4325 2375) BN 9
J 0
(4313 2383);
DISPLAY 0.680851 (4313 2383);
PAINT GREEN (4313 2383);
FORCEPROP 2 LAST CDS_LIB standard
J 0
(4375 2375);
DISPLAY INVISIBLE (4375 2375);
FORCEPROP 1 LAST BODY_TYPE PLUMBING
J 0
(4375 2425);
DISPLAY 0.872340 (4375 2425);
PAINT GREEN (4375 2425);
DISPLAY INVISIBLE (4375 2425);
FORCEPROP 1 LAST HDL_TAP TRUE
J 0
(4700 2250);
DISPLAY 0.872340 (4700 2250);
DISPLAY INVISIBLE (4700 2250);
FORCEPROP 1 LAST PATH I197
J 0
(4373 2375);
DISPLAY 0.872340 (4373 2375);
PAINT GREEN (4373 2375);
DISPLAY INVISIBLE (4373 2375);
FORCEADD TAP..1
(4375 2575);
FORCEPROP 3 LASTPIN (4325 2575) SIG_NAME P5E_CPU1_P2_TX_C_DP<10>
J 0
(4335 2585);
DISPLAY 0.659574 (4335 2585);
PAINT MONO (4335 2585);
DISPLAY INVISIBLE (4335 2585);
FORCEPROP 1 LASTPIN (4325 2575) BN 10
J 0
(4313 2583);
DISPLAY 0.680851 (4313 2583);
PAINT GREEN (4313 2583);
FORCEPROP 2 LAST CDS_LIB standard
J 0
(4375 2575);
DISPLAY INVISIBLE (4375 2575);
FORCEPROP 1 LAST BODY_TYPE PLUMBING
J 0
(4375 2625);
DISPLAY 0.872340 (4375 2625);
PAINT GREEN (4375 2625);
DISPLAY INVISIBLE (4375 2625);
FORCEPROP 1 LAST HDL_TAP TRUE
J 0
(4700 2450);
DISPLAY 0.872340 (4700 2450);
DISPLAY INVISIBLE (4700 2450);
FORCEPROP 1 LAST PATH I198
J 0
(4373 2575);
DISPLAY 0.872340 (4373 2575);
PAINT GREEN (4373 2575);
DISPLAY INVISIBLE (4373 2575);
FORCEADD TAP..1
(4375 2775);
FORCEPROP 3 LASTPIN (4325 2775) SIG_NAME P5E_CPU1_P2_TX_C_DP<11>
J 0
(4335 2785);
DISPLAY 0.659574 (4335 2785);
PAINT MONO (4335 2785);
DISPLAY INVISIBLE (4335 2785);
FORCEPROP 1 LASTPIN (4325 2775) BN 11
J 0
(4313 2783);
DISPLAY 0.680851 (4313 2783);
PAINT GREEN (4313 2783);
FORCEPROP 2 LAST CDS_LIB standard
J 0
(4375 2775);
DISPLAY INVISIBLE (4375 2775);
FORCEPROP 1 LAST BODY_TYPE PLUMBING
J 0
(4375 2825);
DISPLAY 0.872340 (4375 2825);
PAINT GREEN (4375 2825);
DISPLAY INVISIBLE (4375 2825);
FORCEPROP 1 LAST HDL_TAP TRUE
J 0
(4700 2650);
DISPLAY 0.872340 (4700 2650);
DISPLAY INVISIBLE (4700 2650);
FORCEPROP 1 LAST PATH I199
J 0
(4373 2775);
DISPLAY 0.872340 (4373 2775);
PAINT GREEN (4373 2775);
DISPLAY INVISIBLE (4373 2775);
FORCEADD TAP..1
(4375 2975);
FORCEPROP 3 LASTPIN (4325 2975) SIG_NAME P5E_CPU1_P2_TX_C_DP<12>
J 0
(4335 2985);
DISPLAY 0.659574 (4335 2985);
PAINT MONO (4335 2985);
DISPLAY INVISIBLE (4335 2985);
FORCEPROP 1 LASTPIN (4325 2975) BN 12
J 0
(4313 2983);
DISPLAY 0.680851 (4313 2983);
PAINT GREEN (4313 2983);
FORCEPROP 2 LAST CDS_LIB standard
J 0
(4375 2975);
DISPLAY INVISIBLE (4375 2975);
FORCEPROP 1 LAST BODY_TYPE PLUMBING
J 0
(4375 3025);
DISPLAY 0.872340 (4375 3025);
PAINT GREEN (4375 3025);
DISPLAY INVISIBLE (4375 3025);
FORCEPROP 1 LAST HDL_TAP TRUE
J 0
(4700 2850);
DISPLAY 0.872340 (4700 2850);
DISPLAY INVISIBLE (4700 2850);
FORCEPROP 1 LAST PATH I200
J 0
(4373 2975);
DISPLAY 0.872340 (4373 2975);
PAINT GREEN (4373 2975);
DISPLAY INVISIBLE (4373 2975);
FORCEADD TAP..1
(4175 3225);
FORCEPROP 3 LASTPIN (4125 3225) SIG_NAME P5E_CPU1_P2_TX_C_DN<13>
J 0
(4135 3235);
DISPLAY 0.659574 (4135 3235);
PAINT MONO (4135 3235);
DISPLAY INVISIBLE (4135 3235);
FORCEPROP 1 LASTPIN (4125 3225) BN 13
J 0
(4113 3233);
DISPLAY 0.680851 (4113 3233);
PAINT GREEN (4113 3233);
FORCEPROP 2 LAST CDS_LIB standard
J 0
(4175 3225);
DISPLAY INVISIBLE (4175 3225);
FORCEPROP 1 LAST BODY_TYPE PLUMBING
J 0
(4175 3275);
DISPLAY 0.872340 (4175 3275);
PAINT GREEN (4175 3275);
DISPLAY INVISIBLE (4175 3275);
FORCEPROP 1 LAST HDL_TAP TRUE
J 0
(4500 3100);
DISPLAY 0.872340 (4500 3100);
DISPLAY INVISIBLE (4500 3100);
FORCEPROP 1 LAST PATH I201
J 0
(4173 3225);
DISPLAY 0.872340 (4173 3225);
PAINT GREEN (4173 3225);
DISPLAY INVISIBLE (4173 3225);
FORCEADD TAP..1
(4175 3625);
FORCEPROP 3 LASTPIN (4125 3625) SIG_NAME P5E_CPU1_P2_TX_C_DN<15>
J 0
(4135 3635);
DISPLAY 0.659574 (4135 3635);
PAINT MONO (4135 3635);
DISPLAY INVISIBLE (4135 3635);
FORCEPROP 1 LASTPIN (4125 3625) BN 15
J 0
(4113 3633);
DISPLAY 0.680851 (4113 3633);
PAINT GREEN (4113 3633);
FORCEPROP 2 LAST CDS_LIB standard
J 0
(4175 3625);
DISPLAY INVISIBLE (4175 3625);
FORCEPROP 1 LAST BODY_TYPE PLUMBING
J 0
(4175 3675);
DISPLAY 0.872340 (4175 3675);
PAINT GREEN (4175 3675);
DISPLAY INVISIBLE (4175 3675);
FORCEPROP 1 LAST HDL_TAP TRUE
J 0
(4500 3500);
DISPLAY 0.872340 (4500 3500);
DISPLAY INVISIBLE (4500 3500);
FORCEPROP 1 LAST PATH I202
J 0
(4173 3625);
DISPLAY 0.872340 (4173 3625);
PAINT GREEN (4173 3625);
DISPLAY INVISIBLE (4173 3625);
FORCEADD TAP..1
(4175 3425);
FORCEPROP 3 LASTPIN (4125 3425) SIG_NAME P5E_CPU1_P2_TX_C_DN<14>
J 0
(4135 3435);
DISPLAY 0.659574 (4135 3435);
PAINT MONO (4135 3435);
DISPLAY INVISIBLE (4135 3435);
FORCEPROP 1 LASTPIN (4125 3425) BN 14
J 0
(4113 3433);
DISPLAY 0.680851 (4113 3433);
PAINT GREEN (4113 3433);
FORCEPROP 2 LAST CDS_LIB standard
J 0
(4175 3425);
DISPLAY INVISIBLE (4175 3425);
FORCEPROP 1 LAST BODY_TYPE PLUMBING
J 0
(4175 3475);
DISPLAY 0.872340 (4175 3475);
PAINT GREEN (4175 3475);
DISPLAY INVISIBLE (4175 3475);
FORCEPROP 1 LAST HDL_TAP TRUE
J 0
(4500 3300);
DISPLAY 0.872340 (4500 3300);
DISPLAY INVISIBLE (4500 3300);
FORCEPROP 1 LAST PATH I203
J 0
(4173 3425);
DISPLAY 0.872340 (4173 3425);
PAINT GREEN (4173 3425);
DISPLAY INVISIBLE (4173 3425);
FORCEADD TAP..1
(4375 3175);
FORCEPROP 3 LASTPIN (4325 3175) SIG_NAME P5E_CPU1_P2_TX_C_DP<13>
J 0
(4335 3185);
DISPLAY 0.659574 (4335 3185);
PAINT MONO (4335 3185);
DISPLAY INVISIBLE (4335 3185);
FORCEPROP 1 LASTPIN (4325 3175) BN 13
J 0
(4313 3183);
DISPLAY 0.680851 (4313 3183);
PAINT GREEN (4313 3183);
FORCEPROP 2 LAST CDS_LIB standard
J 0
(4375 3175);
DISPLAY INVISIBLE (4375 3175);
FORCEPROP 1 LAST BODY_TYPE PLUMBING
J 0
(4375 3225);
DISPLAY 0.872340 (4375 3225);
PAINT GREEN (4375 3225);
DISPLAY INVISIBLE (4375 3225);
FORCEPROP 1 LAST HDL_TAP TRUE
J 0
(4700 3050);
DISPLAY 0.872340 (4700 3050);
DISPLAY INVISIBLE (4700 3050);
FORCEPROP 1 LAST PATH I204
J 0
(4373 3175);
DISPLAY 0.872340 (4373 3175);
PAINT GREEN (4373 3175);
DISPLAY INVISIBLE (4373 3175);
FORCEADD TAP..1
(4375 3375);
FORCEPROP 3 LASTPIN (4325 3375) SIG_NAME P5E_CPU1_P2_TX_C_DP<14>
J 0
(4335 3385);
DISPLAY 0.659574 (4335 3385);
PAINT MONO (4335 3385);
DISPLAY INVISIBLE (4335 3385);
FORCEPROP 1 LASTPIN (4325 3375) BN 14
J 0
(4313 3383);
DISPLAY 0.680851 (4313 3383);
PAINT GREEN (4313 3383);
FORCEPROP 2 LAST CDS_LIB standard
J 0
(4375 3375);
DISPLAY INVISIBLE (4375 3375);
FORCEPROP 1 LAST BODY_TYPE PLUMBING
J 0
(4375 3425);
DISPLAY 0.872340 (4375 3425);
PAINT GREEN (4375 3425);
DISPLAY INVISIBLE (4375 3425);
FORCEPROP 1 LAST HDL_TAP TRUE
J 0
(4700 3250);
DISPLAY 0.872340 (4700 3250);
DISPLAY INVISIBLE (4700 3250);
FORCEPROP 1 LAST PATH I205
J 0
(4373 3375);
DISPLAY 0.872340 (4373 3375);
PAINT GREEN (4373 3375);
DISPLAY INVISIBLE (4373 3375);
FORCEADD TAP..1
(4375 3575);
FORCEPROP 3 LASTPIN (4325 3575) SIG_NAME P5E_CPU1_P2_TX_C_DP<15>
J 0
(4335 3585);
DISPLAY 0.659574 (4335 3585);
PAINT MONO (4335 3585);
DISPLAY INVISIBLE (4335 3585);
FORCEPROP 1 LASTPIN (4325 3575) BN 15
J 0
(4313 3583);
DISPLAY 0.680851 (4313 3583);
PAINT GREEN (4313 3583);
FORCEPROP 2 LAST CDS_LIB standard
J 0
(4375 3575);
DISPLAY INVISIBLE (4375 3575);
FORCEPROP 1 LAST BODY_TYPE PLUMBING
J 0
(4375 3625);
DISPLAY 0.872340 (4375 3625);
PAINT GREEN (4375 3625);
DISPLAY INVISIBLE (4375 3625);
FORCEPROP 1 LAST HDL_TAP TRUE
J 0
(4700 3450);
DISPLAY 0.872340 (4700 3450);
DISPLAY INVISIBLE (4700 3450);
FORCEPROP 1 LAST PATH I206
J 0
(4373 3575);
DISPLAY 0.872340 (4373 3575);
PAINT GREEN (4373 3575);
DISPLAY INVISIBLE (4373 3575);
FORCEADD OFFPAGE..2
(5375 3650);
FORCEPROP 2 LAST $XR0 339 
J 0
(5564 3650);
DISPLAY 0.638298 (5564 3650);
PAINT MONO (5564 3650);
FORCEPROP 2 LAST CDS_LIB standard
J 0
(5375 3650);
DISPLAY INVISIBLE (5375 3650);
FORCEPROP 1 LAST OFFPAGE TRUE
J 0
(5700 3525);
DISPLAY 0.872340 (5700 3525);
DISPLAY INVISIBLE (5700 3525);
FORCEPROP 1 LAST COMMENT_BODY TRUE
J 0
(5330 3555);
DISPLAY 0.872340 (5330 3555);
PAINT GREEN (5330 3555);
DISPLAY INVISIBLE (5330 3555);
FORCEPROP 2 LAST PATH I207
J 0
(5550 3725);
DISPLAY 1.021277 (5550 3725);
DISPLAY INVISIBLE (5550 3725);
FORCEADD OFFPAGE..2
(5375 3600);
FORCEPROP 2 LAST $XR0 339 
J 0
(5564 3600);
DISPLAY 0.638298 (5564 3600);
PAINT MONO (5564 3600);
FORCEPROP 2 LAST CDS_LIB standard
J 0
(5375 3600);
DISPLAY INVISIBLE (5375 3600);
FORCEPROP 1 LAST OFFPAGE TRUE
J 0
(5700 3475);
DISPLAY 0.872340 (5700 3475);
DISPLAY INVISIBLE (5700 3475);
FORCEPROP 1 LAST COMMENT_BODY TRUE
J 0
(5330 3505);
DISPLAY 0.872340 (5330 3505);
PAINT GREEN (5330 3505);
DISPLAY INVISIBLE (5330 3505);
FORCEPROP 2 LAST PATH I208
J 0
(5550 3675);
DISPLAY 1.021277 (5550 3675);
DISPLAY INVISIBLE (5550 3675);
FORCEADD OFFPAGE..1
(-2875 1650);
FORCEPROP 2 LAST $XR0 51 
J 0
(-3096 1650);
DISPLAY 0.638298 (-3096 1650);
PAINT MONO (-3096 1650);
FORCEPROP 2 LAST CDS_LIB standard
J 0
(-2875 1650);
DISPLAY INVISIBLE (-2875 1650);
FORCEPROP 1 LAST OFFPAGE TRUE
J 0
(-2550 1525);
DISPLAY 0.872340 (-2550 1525);
DISPLAY INVISIBLE (-2550 1525);
FORCEPROP 1 LAST COMMENT_BODY TRUE
J 0
(-2750 1550);
DISPLAY 0.872340 (-2750 1550);
PAINT GREEN (-2750 1550);
DISPLAY INVISIBLE (-2750 1550);
FORCEPROP 2 LAST PATH I209
J 0
(-3150 1700);
DISPLAY 1.021277 (-3150 1700);
DISPLAY INVISIBLE (-3150 1700);
FORCEADD OFFPAGE..1
(-2875 1600);
FORCEPROP 2 LAST $XR0 51 
J 0
(-3096 1600);
DISPLAY 0.638298 (-3096 1600);
PAINT MONO (-3096 1600);
FORCEPROP 2 LAST CDS_LIB standard
J 0
(-2875 1600);
DISPLAY INVISIBLE (-2875 1600);
FORCEPROP 1 LAST OFFPAGE TRUE
J 0
(-2550 1475);
DISPLAY 0.872340 (-2550 1475);
DISPLAY INVISIBLE (-2550 1475);
FORCEPROP 1 LAST COMMENT_BODY TRUE
J 0
(-2750 1500);
DISPLAY 0.872340 (-2750 1500);
PAINT GREEN (-2750 1500);
DISPLAY INVISIBLE (-2750 1500);
FORCEPROP 2 LAST PATH I210
J 0
(-3150 1650);
DISPLAY 1.021277 (-3150 1650);
DISPLAY INVISIBLE (-3150 1650);
FORCEADD OFFPAGE..1
(-2875 3575);
FORCEPROP 2 LAST $XR0 51 
J 0
(-3096 3575);
DISPLAY 0.638298 (-3096 3575);
PAINT MONO (-3096 3575);
FORCEPROP 2 LAST CDS_LIB standard
J 0
(-2875 3575);
DISPLAY INVISIBLE (-2875 3575);
FORCEPROP 1 LAST OFFPAGE TRUE
J 0
(-2550 3450);
DISPLAY 0.872340 (-2550 3450);
DISPLAY INVISIBLE (-2550 3450);
FORCEPROP 1 LAST COMMENT_BODY TRUE
J 0
(-2750 3475);
DISPLAY 0.872340 (-2750 3475);
PAINT GREEN (-2750 3475);
DISPLAY INVISIBLE (-2750 3475);
FORCEPROP 2 LAST PATH I211
J 0
(-3150 3625);
DISPLAY 1.021277 (-3150 3625);
DISPLAY INVISIBLE (-3150 3625);
FORCEADD OFFPAGE..1
(-2875 3625);
FORCEPROP 2 LAST $XR0 51 
J 0
(-3096 3625);
DISPLAY 0.638298 (-3096 3625);
PAINT MONO (-3096 3625);
FORCEPROP 2 LAST CDS_LIB standard
J 0
(-2875 3625);
DISPLAY INVISIBLE (-2875 3625);
FORCEPROP 1 LAST OFFPAGE TRUE
J 0
(-2550 3500);
DISPLAY 0.872340 (-2550 3500);
DISPLAY INVISIBLE (-2550 3500);
FORCEPROP 1 LAST COMMENT_BODY TRUE
J 0
(-2750 3525);
DISPLAY 0.872340 (-2750 3525);
PAINT GREEN (-2750 3525);
DISPLAY INVISIBLE (-2750 3525);
FORCEPROP 2 LAST PATH I212
J 0
(-3150 3675);
DISPLAY 1.021277 (-3150 3675);
DISPLAY INVISIBLE (-3150 3675);
FORCEADD TAP..1
R 2
(-1925 175);
FORCEPROP 3 LASTPIN (-1875 175) SIG_NAME P5E_CPU1_P1_TX_DP<0>
J 0
(-1865 185);
DISPLAY 0.659574 (-1865 185);
PAINT MONO (-1865 185);
DISPLAY INVISIBLE (-1865 185);
FORCEPROP 1 LASTPIN (-1875 175) BN 0
J 2
(-1863 183);
DISPLAY 0.680851 (-1863 183);
PAINT GREEN (-1863 183);
FORCEPROP 2 LAST CDS_LIB standard
J 0
(-1925 175);
DISPLAY INVISIBLE (-1925 175);
FORCEPROP 1 LAST BODY_TYPE PLUMBING
J 2
(-1925 225);
DISPLAY 0.872340 (-1925 225);
PAINT GREEN (-1925 225);
DISPLAY INVISIBLE (-1925 225);
FORCEPROP 1 LAST HDL_TAP TRUE
J 2
(-2250 50);
DISPLAY 0.872340 (-2250 50);
DISPLAY INVISIBLE (-2250 50);
FORCEPROP 1 LAST PATH I213
J 2
(-1923 175);
DISPLAY 0.872340 (-1923 175);
PAINT GREEN (-1923 175);
DISPLAY INVISIBLE (-1923 175);
FORCEADD TAP..1
R 2
(-1925 375);
FORCEPROP 3 LASTPIN (-1875 375) SIG_NAME P5E_CPU1_P1_TX_DP<1>
J 0
(-1865 385);
DISPLAY 0.659574 (-1865 385);
PAINT MONO (-1865 385);
DISPLAY INVISIBLE (-1865 385);
FORCEPROP 1 LASTPIN (-1875 375) BN 1
J 2
(-1863 383);
DISPLAY 0.680851 (-1863 383);
PAINT GREEN (-1863 383);
FORCEPROP 2 LAST CDS_LIB standard
J 0
(-1925 375);
DISPLAY INVISIBLE (-1925 375);
FORCEPROP 1 LAST BODY_TYPE PLUMBING
J 2
(-1925 425);
DISPLAY 0.872340 (-1925 425);
PAINT GREEN (-1925 425);
DISPLAY INVISIBLE (-1925 425);
FORCEPROP 1 LAST HDL_TAP TRUE
J 2
(-2250 250);
DISPLAY 0.872340 (-2250 250);
DISPLAY INVISIBLE (-2250 250);
FORCEPROP 1 LAST PATH I214
J 2
(-1923 375);
DISPLAY 0.872340 (-1923 375);
PAINT GREEN (-1923 375);
DISPLAY INVISIBLE (-1923 375);
FORCEADD TAP..1
R 2
(-1675 225);
FORCEPROP 3 LASTPIN (-1625 225) SIG_NAME P5E_CPU1_P1_TX_DN<0>
J 0
(-1615 235);
DISPLAY 0.659574 (-1615 235);
PAINT MONO (-1615 235);
DISPLAY INVISIBLE (-1615 235);
FORCEPROP 1 LASTPIN (-1625 225) BN 0
J 2
(-1613 233);
DISPLAY 0.680851 (-1613 233);
PAINT GREEN (-1613 233);
FORCEPROP 2 LAST CDS_LIB standard
J 0
(-1675 225);
DISPLAY INVISIBLE (-1675 225);
FORCEPROP 1 LAST BODY_TYPE PLUMBING
J 2
(-1675 275);
DISPLAY 0.872340 (-1675 275);
PAINT GREEN (-1675 275);
DISPLAY INVISIBLE (-1675 275);
FORCEPROP 1 LAST HDL_TAP TRUE
J 2
(-2000 100);
DISPLAY 0.872340 (-2000 100);
DISPLAY INVISIBLE (-2000 100);
FORCEPROP 1 LAST PATH I215
J 2
(-1673 225);
DISPLAY 0.872340 (-1673 225);
PAINT GREEN (-1673 225);
DISPLAY INVISIBLE (-1673 225);
FORCEADD TAP..1
R 2
(-1675 425);
FORCEPROP 3 LASTPIN (-1625 425) SIG_NAME P5E_CPU1_P1_TX_DN<1>
J 0
(-1615 435);
DISPLAY 0.659574 (-1615 435);
PAINT MONO (-1615 435);
DISPLAY INVISIBLE (-1615 435);
FORCEPROP 1 LASTPIN (-1625 425) BN 1
J 2
(-1613 433);
DISPLAY 0.680851 (-1613 433);
PAINT GREEN (-1613 433);
FORCEPROP 2 LAST CDS_LIB standard
J 0
(-1675 425);
DISPLAY INVISIBLE (-1675 425);
FORCEPROP 1 LAST BODY_TYPE PLUMBING
J 2
(-1675 475);
DISPLAY 0.872340 (-1675 475);
PAINT GREEN (-1675 475);
DISPLAY INVISIBLE (-1675 475);
FORCEPROP 1 LAST HDL_TAP TRUE
J 2
(-2000 300);
DISPLAY 0.872340 (-2000 300);
DISPLAY INVISIBLE (-2000 300);
FORCEPROP 1 LAST PATH I216
J 2
(-1673 425);
DISPLAY 0.872340 (-1673 425);
PAINT GREEN (-1673 425);
DISPLAY INVISIBLE (-1673 425);
FORCEADD TAP..1
R 2
(-1925 575);
FORCEPROP 3 LASTPIN (-1875 575) SIG_NAME P5E_CPU1_P1_TX_DP<2>
J 0
(-1865 585);
DISPLAY 0.659574 (-1865 585);
PAINT MONO (-1865 585);
DISPLAY INVISIBLE (-1865 585);
FORCEPROP 1 LASTPIN (-1875 575) BN 2
J 2
(-1863 583);
DISPLAY 0.680851 (-1863 583);
PAINT GREEN (-1863 583);
FORCEPROP 2 LAST CDS_LIB standard
J 0
(-1925 575);
DISPLAY INVISIBLE (-1925 575);
FORCEPROP 1 LAST BODY_TYPE PLUMBING
J 2
(-1925 625);
DISPLAY 0.872340 (-1925 625);
PAINT GREEN (-1925 625);
DISPLAY INVISIBLE (-1925 625);
FORCEPROP 1 LAST HDL_TAP TRUE
J 2
(-2250 450);
DISPLAY 0.872340 (-2250 450);
DISPLAY INVISIBLE (-2250 450);
FORCEPROP 1 LAST PATH I217
J 2
(-1923 575);
DISPLAY 0.872340 (-1923 575);
PAINT GREEN (-1923 575);
DISPLAY INVISIBLE (-1923 575);
FORCEADD TAP..1
R 2
(-1925 775);
FORCEPROP 3 LASTPIN (-1875 775) SIG_NAME P5E_CPU1_P1_TX_DP<3>
J 0
(-1865 785);
DISPLAY 0.659574 (-1865 785);
PAINT MONO (-1865 785);
DISPLAY INVISIBLE (-1865 785);
FORCEPROP 1 LASTPIN (-1875 775) BN 3
J 2
(-1863 783);
DISPLAY 0.680851 (-1863 783);
PAINT GREEN (-1863 783);
FORCEPROP 2 LAST CDS_LIB standard
J 0
(-1925 775);
DISPLAY INVISIBLE (-1925 775);
FORCEPROP 1 LAST BODY_TYPE PLUMBING
J 2
(-1925 825);
DISPLAY 0.872340 (-1925 825);
PAINT GREEN (-1925 825);
DISPLAY INVISIBLE (-1925 825);
FORCEPROP 1 LAST HDL_TAP TRUE
J 2
(-2250 650);
DISPLAY 0.872340 (-2250 650);
DISPLAY INVISIBLE (-2250 650);
FORCEPROP 1 LAST PATH I218
J 2
(-1923 775);
DISPLAY 0.872340 (-1923 775);
PAINT GREEN (-1923 775);
DISPLAY INVISIBLE (-1923 775);
FORCEADD TAP..1
R 2
(-1925 975);
FORCEPROP 3 LASTPIN (-1875 975) SIG_NAME P5E_CPU1_P1_TX_DP<4>
J 0
(-1865 985);
DISPLAY 0.659574 (-1865 985);
PAINT MONO (-1865 985);
DISPLAY INVISIBLE (-1865 985);
FORCEPROP 1 LASTPIN (-1875 975) BN 4
J 2
(-1863 983);
DISPLAY 0.680851 (-1863 983);
PAINT GREEN (-1863 983);
FORCEPROP 2 LAST CDS_LIB standard
J 0
(-1925 975);
DISPLAY INVISIBLE (-1925 975);
FORCEPROP 1 LAST BODY_TYPE PLUMBING
J 2
(-1925 1025);
DISPLAY 0.872340 (-1925 1025);
PAINT GREEN (-1925 1025);
DISPLAY INVISIBLE (-1925 1025);
FORCEPROP 1 LAST HDL_TAP TRUE
J 2
(-2250 850);
DISPLAY 0.872340 (-2250 850);
DISPLAY INVISIBLE (-2250 850);
FORCEPROP 1 LAST PATH I219
J 2
(-1923 975);
DISPLAY 0.872340 (-1923 975);
PAINT GREEN (-1923 975);
DISPLAY INVISIBLE (-1923 975);
FORCEADD TAP..1
R 2
(-1675 625);
FORCEPROP 3 LASTPIN (-1625 625) SIG_NAME P5E_CPU1_P1_TX_DN<2>
J 0
(-1615 635);
DISPLAY 0.659574 (-1615 635);
PAINT MONO (-1615 635);
DISPLAY INVISIBLE (-1615 635);
FORCEPROP 1 LASTPIN (-1625 625) BN 2
J 2
(-1613 633);
DISPLAY 0.680851 (-1613 633);
PAINT GREEN (-1613 633);
FORCEPROP 2 LAST CDS_LIB standard
J 0
(-1675 625);
DISPLAY INVISIBLE (-1675 625);
FORCEPROP 1 LAST BODY_TYPE PLUMBING
J 2
(-1675 675);
DISPLAY 0.872340 (-1675 675);
PAINT GREEN (-1675 675);
DISPLAY INVISIBLE (-1675 675);
FORCEPROP 1 LAST HDL_TAP TRUE
J 2
(-2000 500);
DISPLAY 0.872340 (-2000 500);
DISPLAY INVISIBLE (-2000 500);
FORCEPROP 1 LAST PATH I220
J 2
(-1673 625);
DISPLAY 0.872340 (-1673 625);
PAINT GREEN (-1673 625);
DISPLAY INVISIBLE (-1673 625);
FORCEADD TAP..1
R 2
(-1675 825);
FORCEPROP 3 LASTPIN (-1625 825) SIG_NAME P5E_CPU1_P1_TX_DN<3>
J 0
(-1615 835);
DISPLAY 0.659574 (-1615 835);
PAINT MONO (-1615 835);
DISPLAY INVISIBLE (-1615 835);
FORCEPROP 1 LASTPIN (-1625 825) BN 3
J 2
(-1613 833);
DISPLAY 0.680851 (-1613 833);
PAINT GREEN (-1613 833);
FORCEPROP 2 LAST CDS_LIB standard
J 0
(-1675 825);
DISPLAY INVISIBLE (-1675 825);
FORCEPROP 1 LAST BODY_TYPE PLUMBING
J 2
(-1675 875);
DISPLAY 0.872340 (-1675 875);
PAINT GREEN (-1675 875);
DISPLAY INVISIBLE (-1675 875);
FORCEPROP 1 LAST HDL_TAP TRUE
J 2
(-2000 700);
DISPLAY 0.872340 (-2000 700);
DISPLAY INVISIBLE (-2000 700);
FORCEPROP 1 LAST PATH I221
J 2
(-1673 825);
DISPLAY 0.872340 (-1673 825);
PAINT GREEN (-1673 825);
DISPLAY INVISIBLE (-1673 825);
FORCEADD TAP..1
R 2
(-1925 1175);
FORCEPROP 3 LASTPIN (-1875 1175) SIG_NAME P5E_CPU1_P1_TX_DP<5>
J 0
(-1865 1185);
DISPLAY 0.659574 (-1865 1185);
PAINT MONO (-1865 1185);
DISPLAY INVISIBLE (-1865 1185);
FORCEPROP 1 LASTPIN (-1875 1175) BN 5
J 2
(-1863 1183);
DISPLAY 0.680851 (-1863 1183);
PAINT GREEN (-1863 1183);
FORCEPROP 2 LAST CDS_LIB standard
J 0
(-1925 1175);
DISPLAY INVISIBLE (-1925 1175);
FORCEPROP 1 LAST BODY_TYPE PLUMBING
J 2
(-1925 1225);
DISPLAY 0.872340 (-1925 1225);
PAINT GREEN (-1925 1225);
DISPLAY INVISIBLE (-1925 1225);
FORCEPROP 1 LAST HDL_TAP TRUE
J 2
(-2250 1050);
DISPLAY 0.872340 (-2250 1050);
DISPLAY INVISIBLE (-2250 1050);
FORCEPROP 1 LAST PATH I222
J 2
(-1923 1175);
DISPLAY 0.872340 (-1923 1175);
PAINT GREEN (-1923 1175);
DISPLAY INVISIBLE (-1923 1175);
FORCEADD TAP..1
R 2
(-1925 1375);
FORCEPROP 3 LASTPIN (-1875 1375) SIG_NAME P5E_CPU1_P1_TX_DP<6>
J 0
(-1865 1385);
DISPLAY 0.659574 (-1865 1385);
PAINT MONO (-1865 1385);
DISPLAY INVISIBLE (-1865 1385);
FORCEPROP 1 LASTPIN (-1875 1375) BN 6
J 2
(-1863 1383);
DISPLAY 0.680851 (-1863 1383);
PAINT GREEN (-1863 1383);
FORCEPROP 2 LAST CDS_LIB standard
J 0
(-1925 1375);
DISPLAY INVISIBLE (-1925 1375);
FORCEPROP 1 LAST BODY_TYPE PLUMBING
J 2
(-1925 1425);
DISPLAY 0.872340 (-1925 1425);
PAINT GREEN (-1925 1425);
DISPLAY INVISIBLE (-1925 1425);
FORCEPROP 1 LAST HDL_TAP TRUE
J 2
(-2250 1250);
DISPLAY 0.872340 (-2250 1250);
DISPLAY INVISIBLE (-2250 1250);
FORCEPROP 1 LAST PATH I223
J 2
(-1923 1375);
DISPLAY 0.872340 (-1923 1375);
PAINT GREEN (-1923 1375);
DISPLAY INVISIBLE (-1923 1375);
FORCEADD TAP..1
R 2
(-1675 1225);
FORCEPROP 3 LASTPIN (-1625 1225) SIG_NAME P5E_CPU1_P1_TX_DN<5>
J 0
(-1615 1235);
DISPLAY 0.659574 (-1615 1235);
PAINT MONO (-1615 1235);
DISPLAY INVISIBLE (-1615 1235);
FORCEPROP 1 LASTPIN (-1625 1225) BN 5
J 2
(-1613 1233);
DISPLAY 0.680851 (-1613 1233);
PAINT GREEN (-1613 1233);
FORCEPROP 2 LAST CDS_LIB standard
J 0
(-1675 1225);
DISPLAY INVISIBLE (-1675 1225);
FORCEPROP 1 LAST BODY_TYPE PLUMBING
J 2
(-1675 1275);
DISPLAY 0.872340 (-1675 1275);
PAINT GREEN (-1675 1275);
DISPLAY INVISIBLE (-1675 1275);
FORCEPROP 1 LAST HDL_TAP TRUE
J 2
(-2000 1100);
DISPLAY 0.872340 (-2000 1100);
DISPLAY INVISIBLE (-2000 1100);
FORCEPROP 1 LAST PATH I224
J 2
(-1673 1225);
DISPLAY 0.872340 (-1673 1225);
PAINT GREEN (-1673 1225);
DISPLAY INVISIBLE (-1673 1225);
FORCEADD TAP..1
R 2
(-1675 1025);
FORCEPROP 3 LASTPIN (-1625 1025) SIG_NAME P5E_CPU1_P1_TX_DN<4>
J 0
(-1615 1035);
DISPLAY 0.659574 (-1615 1035);
PAINT MONO (-1615 1035);
DISPLAY INVISIBLE (-1615 1035);
FORCEPROP 1 LASTPIN (-1625 1025) BN 4
J 2
(-1613 1033);
DISPLAY 0.680851 (-1613 1033);
PAINT GREEN (-1613 1033);
FORCEPROP 2 LAST CDS_LIB standard
J 0
(-1675 1025);
DISPLAY INVISIBLE (-1675 1025);
FORCEPROP 1 LAST BODY_TYPE PLUMBING
J 2
(-1675 1075);
DISPLAY 0.872340 (-1675 1075);
PAINT GREEN (-1675 1075);
DISPLAY INVISIBLE (-1675 1075);
FORCEPROP 1 LAST HDL_TAP TRUE
J 2
(-2000 900);
DISPLAY 0.872340 (-2000 900);
DISPLAY INVISIBLE (-2000 900);
FORCEPROP 1 LAST PATH I225
J 2
(-1673 1025);
DISPLAY 0.872340 (-1673 1025);
PAINT GREEN (-1673 1025);
DISPLAY INVISIBLE (-1673 1025);
FORCEADD TAP..1
R 2
(-1675 1425);
FORCEPROP 3 LASTPIN (-1625 1425) SIG_NAME P5E_CPU1_P1_TX_DN<6>
J 0
(-1615 1435);
DISPLAY 0.659574 (-1615 1435);
PAINT MONO (-1615 1435);
DISPLAY INVISIBLE (-1615 1435);
FORCEPROP 1 LASTPIN (-1625 1425) BN 6
J 2
(-1613 1433);
DISPLAY 0.680851 (-1613 1433);
PAINT GREEN (-1613 1433);
FORCEPROP 2 LAST CDS_LIB standard
J 0
(-1675 1425);
DISPLAY INVISIBLE (-1675 1425);
FORCEPROP 1 LAST BODY_TYPE PLUMBING
J 2
(-1675 1475);
DISPLAY 0.872340 (-1675 1475);
PAINT GREEN (-1675 1475);
DISPLAY INVISIBLE (-1675 1475);
FORCEPROP 1 LAST HDL_TAP TRUE
J 2
(-2000 1300);
DISPLAY 0.872340 (-2000 1300);
DISPLAY INVISIBLE (-2000 1300);
FORCEPROP 1 LAST PATH I226
J 2
(-1673 1425);
DISPLAY 0.872340 (-1673 1425);
PAINT GREEN (-1673 1425);
DISPLAY INVISIBLE (-1673 1425);
FORCEADD TAP..1
R 2
(-1925 1575);
FORCEPROP 3 LASTPIN (-1875 1575) SIG_NAME P5E_CPU1_P1_TX_DP<7>
J 0
(-1865 1585);
DISPLAY 0.659574 (-1865 1585);
PAINT MONO (-1865 1585);
DISPLAY INVISIBLE (-1865 1585);
FORCEPROP 1 LASTPIN (-1875 1575) BN 7
J 2
(-1863 1583);
DISPLAY 0.680851 (-1863 1583);
PAINT GREEN (-1863 1583);
FORCEPROP 2 LAST CDS_LIB standard
J 0
(-1925 1575);
DISPLAY INVISIBLE (-1925 1575);
FORCEPROP 1 LAST BODY_TYPE PLUMBING
J 2
(-1925 1625);
DISPLAY 0.872340 (-1925 1625);
PAINT GREEN (-1925 1625);
DISPLAY INVISIBLE (-1925 1625);
FORCEPROP 1 LAST HDL_TAP TRUE
J 2
(-2250 1450);
DISPLAY 0.872340 (-2250 1450);
DISPLAY INVISIBLE (-2250 1450);
FORCEPROP 1 LAST PATH I227
J 2
(-1923 1575);
DISPLAY 0.872340 (-1923 1575);
PAINT GREEN (-1923 1575);
DISPLAY INVISIBLE (-1923 1575);
FORCEADD TAP..1
R 2
(-1675 1625);
FORCEPROP 3 LASTPIN (-1625 1625) SIG_NAME P5E_CPU1_P1_TX_DN<7>
J 0
(-1615 1635);
DISPLAY 0.659574 (-1615 1635);
PAINT MONO (-1615 1635);
DISPLAY INVISIBLE (-1615 1635);
FORCEPROP 1 LASTPIN (-1625 1625) BN 7
J 2
(-1613 1633);
DISPLAY 0.680851 (-1613 1633);
PAINT GREEN (-1613 1633);
FORCEPROP 2 LAST CDS_LIB standard
J 0
(-1675 1625);
DISPLAY INVISIBLE (-1675 1625);
FORCEPROP 1 LAST BODY_TYPE PLUMBING
J 2
(-1675 1675);
DISPLAY 0.872340 (-1675 1675);
PAINT GREEN (-1675 1675);
DISPLAY INVISIBLE (-1675 1675);
FORCEPROP 1 LAST HDL_TAP TRUE
J 2
(-2000 1500);
DISPLAY 0.872340 (-2000 1500);
DISPLAY INVISIBLE (-2000 1500);
FORCEPROP 1 LAST PATH I228
J 2
(-1673 1625);
DISPLAY 0.872340 (-1673 1625);
PAINT GREEN (-1673 1625);
DISPLAY INVISIBLE (-1673 1625);
FORCEADD Q_CAP_DIFFBUS..2
R 2
(-950 225);
FORCEPROP 1 LAST LOCATION C740
J 2
(-716 242);
DISPLAY 0.723404 (-716 242);
PAINT GREEN (-716 242);
FORCEPROP 2 LAST $SEC 1
J 2
(-775 300);
DISPLAY 0.680851 (-775 300);
PAINT MONO (-775 300);
DISPLAY INVISIBLE (-775 300);
FORCEPROP 2 LAST CDS_SEC 1
J 2
(-775 300);
DISPLAY 0.680851 (-775 300);
DISPLAY INVISIBLE (-775 300);
FORCEPROP 2 LASTPIN (-875 225) $PN 1
J 0
(-865 235);
DISPLAY 0.808511 (-865 235);
FORCEPROP 2 LASTPIN (-1025 225) $PN 2
J 2
(-1035 235);
DISPLAY 0.808511 (-1035 235);
FORCEPROP 2 LAST VALUE DIFF BUS_0.22UF
J 2
(-1100 225);
DISPLAY 0.553191 (-1100 225);
FORCEPROP 1 LAST PIN_NAMES_ROTATE TRUE
J 2
(-950 225);
DISPLAY 0.489362 (-950 225);
PAINT GREEN (-950 225);
DISPLAY INVISIBLE (-950 225);
FORCEPROP 2 LAST CDS_LIB pure_quanta
J 2
(-950 225);
DISPLAY INVISIBLE (-950 225);
FORCEPROP 1 LAST CDS_LMAN_SYM_OUTLINE -25,50,25,-50
J 2
(-950 225);
DISPLAY 0.468085 (-950 225);
PAINT GREEN (-950 225);
DISPLAY INVISIBLE (-950 225);
FORCEPROP 2 LAST VOLTAGE 6.3V
J 2
(-1300 275);
DISPLAY 0.553191 (-1300 275);
DISPLAY INVISIBLE (-1300 275);
FORCEPROP 1 LAST MATERIAL X6S
J 2
(-941 304);
DISPLAY 0.574468 (-941 304);
PAINT GREEN (-941 304);
DISPLAY INVISIBLE (-941 304);
FORCEPROP 2 LAST PACK_TYPE C0201
J 2
(-1125 275);
DISPLAY 0.553191 (-1125 275);
DISPLAY INVISIBLE (-1125 275);
FORCEPROP 2 LAST TOLERANCE 20%
J 2
(-1025 275);
DISPLAY 0.553191 (-1025 275);
DISPLAY INVISIBLE (-1025 275);
FORCEPROP 1 LAST PART_NUMBER SP_CH4221MEE01
J 2
(-1066 313);
DISPLAY 0.574468 (-1066 313);
PAINT GREEN (-1066 313);
DISPLAY INVISIBLE (-1066 313);
FORCEPROP 1 LAST LOCATION C740
J 0
(-700 300);
DISPLAY 1.021277 (-700 300);
DISPLAY INVISIBLE (-700 300);
FORCEPROP 1 LAST PATH I229
J 2
(-950 225);
DISPLAY 0.723404 (-950 225);
DISPLAY INVISIBLE (-950 225);
FORCEADD Q_CAP_DIFFBUS..2
R 2
(-950 175);
FORCEPROP 1 LAST LOCATION C741
J 2
(-716 192);
DISPLAY 0.723404 (-716 192);
PAINT GREEN (-716 192);
FORCEPROP 2 LAST $SEC 1
J 2
(-775 250);
DISPLAY 0.680851 (-775 250);
PAINT MONO (-775 250);
DISPLAY INVISIBLE (-775 250);
FORCEPROP 2 LAST CDS_SEC 1
J 2
(-775 250);
DISPLAY 0.680851 (-775 250);
DISPLAY INVISIBLE (-775 250);
FORCEPROP 2 LASTPIN (-875 175) $PN 1
J 0
(-865 185);
DISPLAY 0.808511 (-865 185);
FORCEPROP 2 LASTPIN (-1025 175) $PN 2
J 2
(-1035 185);
DISPLAY 0.808511 (-1035 185);
FORCEPROP 2 LAST VALUE DIFF BUS_0.22UF
J 2
(-1100 175);
DISPLAY 0.553191 (-1100 175);
FORCEPROP 1 LAST PIN_NAMES_ROTATE TRUE
J 2
(-950 175);
DISPLAY 0.489362 (-950 175);
PAINT GREEN (-950 175);
DISPLAY INVISIBLE (-950 175);
FORCEPROP 2 LAST CDS_LIB pure_quanta
J 2
(-950 175);
DISPLAY INVISIBLE (-950 175);
FORCEPROP 1 LAST CDS_LMAN_SYM_OUTLINE -25,50,25,-50
J 2
(-950 175);
DISPLAY 0.468085 (-950 175);
PAINT GREEN (-950 175);
DISPLAY INVISIBLE (-950 175);
FORCEPROP 2 LAST VOLTAGE 6.3V
J 2
(-1300 225);
DISPLAY 0.553191 (-1300 225);
DISPLAY INVISIBLE (-1300 225);
FORCEPROP 1 LAST MATERIAL X6S
J 2
(-941 254);
DISPLAY 0.574468 (-941 254);
PAINT GREEN (-941 254);
DISPLAY INVISIBLE (-941 254);
FORCEPROP 2 LAST PACK_TYPE C0201
J 2
(-1125 225);
DISPLAY 0.553191 (-1125 225);
DISPLAY INVISIBLE (-1125 225);
FORCEPROP 2 LAST TOLERANCE 20%
J 2
(-1025 225);
DISPLAY 0.553191 (-1025 225);
DISPLAY INVISIBLE (-1025 225);
FORCEPROP 1 LAST PART_NUMBER SP_CH4221MEE01
J 2
(-1066 263);
DISPLAY 0.574468 (-1066 263);
PAINT GREEN (-1066 263);
DISPLAY INVISIBLE (-1066 263);
FORCEPROP 1 LAST LOCATION C741
J 0
(-700 250);
DISPLAY 1.021277 (-700 250);
DISPLAY INVISIBLE (-700 250);
FORCEPROP 1 LAST PATH I230
J 2
(-950 175);
DISPLAY 0.723404 (-950 175);
DISPLAY INVISIBLE (-950 175);
FORCEADD Q_CAP_DIFFBUS..2
R 2
(-950 375);
FORCEPROP 1 LAST LOCATION C739
J 2
(-716 392);
DISPLAY 0.723404 (-716 392);
PAINT GREEN (-716 392);
FORCEPROP 2 LAST $SEC 1
J 2
(-775 450);
DISPLAY 0.680851 (-775 450);
PAINT MONO (-775 450);
DISPLAY INVISIBLE (-775 450);
FORCEPROP 2 LAST CDS_SEC 1
J 2
(-775 450);
DISPLAY 0.680851 (-775 450);
DISPLAY INVISIBLE (-775 450);
FORCEPROP 2 LASTPIN (-875 375) $PN 1
J 0
(-865 385);
DISPLAY 0.808511 (-865 385);
FORCEPROP 2 LASTPIN (-1025 375) $PN 2
J 2
(-1035 385);
DISPLAY 0.808511 (-1035 385);
FORCEPROP 2 LAST VALUE DIFF BUS_0.22UF
J 2
(-1100 375);
DISPLAY 0.553191 (-1100 375);
FORCEPROP 1 LAST PIN_NAMES_ROTATE TRUE
J 2
(-950 375);
DISPLAY 0.489362 (-950 375);
PAINT GREEN (-950 375);
DISPLAY INVISIBLE (-950 375);
FORCEPROP 2 LAST CDS_LIB pure_quanta
J 2
(-950 375);
DISPLAY INVISIBLE (-950 375);
FORCEPROP 1 LAST CDS_LMAN_SYM_OUTLINE -25,50,25,-50
J 2
(-950 375);
DISPLAY 0.468085 (-950 375);
PAINT GREEN (-950 375);
DISPLAY INVISIBLE (-950 375);
FORCEPROP 2 LAST VOLTAGE 6.3V
J 2
(-1300 425);
DISPLAY 0.553191 (-1300 425);
DISPLAY INVISIBLE (-1300 425);
FORCEPROP 1 LAST MATERIAL X6S
J 2
(-941 454);
DISPLAY 0.574468 (-941 454);
PAINT GREEN (-941 454);
DISPLAY INVISIBLE (-941 454);
FORCEPROP 2 LAST PACK_TYPE C0201
J 2
(-1125 425);
DISPLAY 0.553191 (-1125 425);
DISPLAY INVISIBLE (-1125 425);
FORCEPROP 2 LAST TOLERANCE 20%
J 2
(-1025 425);
DISPLAY 0.553191 (-1025 425);
DISPLAY INVISIBLE (-1025 425);
FORCEPROP 1 LAST PART_NUMBER SP_CH4221MEE01
J 2
(-1066 463);
DISPLAY 0.574468 (-1066 463);
PAINT GREEN (-1066 463);
DISPLAY INVISIBLE (-1066 463);
FORCEPROP 1 LAST LOCATION C739
J 0
(-700 450);
DISPLAY 1.021277 (-700 450);
DISPLAY INVISIBLE (-700 450);
FORCEPROP 1 LAST PATH I231
J 2
(-950 375);
DISPLAY 0.723404 (-950 375);
DISPLAY INVISIBLE (-950 375);
FORCEADD Q_CAP_DIFFBUS..2
R 2
(-950 425);
FORCEPROP 1 LAST LOCATION C738
J 2
(-716 442);
DISPLAY 0.723404 (-716 442);
PAINT GREEN (-716 442);
FORCEPROP 2 LAST $SEC 1
J 2
(-775 500);
DISPLAY 0.680851 (-775 500);
PAINT MONO (-775 500);
DISPLAY INVISIBLE (-775 500);
FORCEPROP 2 LAST CDS_SEC 1
J 2
(-775 500);
DISPLAY 0.680851 (-775 500);
DISPLAY INVISIBLE (-775 500);
FORCEPROP 2 LASTPIN (-875 425) $PN 1
J 0
(-865 435);
DISPLAY 0.808511 (-865 435);
FORCEPROP 2 LASTPIN (-1025 425) $PN 2
J 2
(-1035 435);
DISPLAY 0.808511 (-1035 435);
FORCEPROP 2 LAST VALUE DIFF BUS_0.22UF
J 2
(-1100 425);
DISPLAY 0.553191 (-1100 425);
FORCEPROP 1 LAST PIN_NAMES_ROTATE TRUE
J 2
(-950 425);
DISPLAY 0.489362 (-950 425);
PAINT GREEN (-950 425);
DISPLAY INVISIBLE (-950 425);
FORCEPROP 1 LAST CDS_LMAN_SYM_OUTLINE -25,50,25,-50
J 2
(-950 425);
DISPLAY 0.468085 (-950 425);
PAINT GREEN (-950 425);
DISPLAY INVISIBLE (-950 425);
FORCEPROP 2 LAST CDS_LIB pure_quanta
J 2
(-950 425);
DISPLAY INVISIBLE (-950 425);
FORCEPROP 2 LAST VOLTAGE 6.3V
J 2
(-1300 475);
DISPLAY 0.553191 (-1300 475);
DISPLAY INVISIBLE (-1300 475);
FORCEPROP 1 LAST MATERIAL X6S
J 2
(-941 504);
DISPLAY 0.574468 (-941 504);
PAINT GREEN (-941 504);
DISPLAY INVISIBLE (-941 504);
FORCEPROP 2 LAST PACK_TYPE C0201
J 2
(-1125 475);
DISPLAY 0.553191 (-1125 475);
DISPLAY INVISIBLE (-1125 475);
FORCEPROP 2 LAST TOLERANCE 20%
J 2
(-1025 475);
DISPLAY 0.553191 (-1025 475);
DISPLAY INVISIBLE (-1025 475);
FORCEPROP 1 LAST PART_NUMBER SP_CH4221MEE01
J 2
(-1066 513);
DISPLAY 0.574468 (-1066 513);
PAINT GREEN (-1066 513);
DISPLAY INVISIBLE (-1066 513);
FORCEPROP 1 LAST LOCATION C738
J 0
(-700 500);
DISPLAY 1.021277 (-700 500);
DISPLAY INVISIBLE (-700 500);
FORCEPROP 1 LAST PATH I232
J 2
(-950 425);
DISPLAY 0.723404 (-950 425);
DISPLAY INVISIBLE (-950 425);
FORCEADD Q_CAP_DIFFBUS..2
R 2
(-950 575);
FORCEPROP 1 LAST LOCATION C737
J 2
(-716 592);
DISPLAY 0.723404 (-716 592);
PAINT GREEN (-716 592);
FORCEPROP 2 LAST $SEC 1
J 2
(-775 650);
DISPLAY 0.680851 (-775 650);
PAINT MONO (-775 650);
DISPLAY INVISIBLE (-775 650);
FORCEPROP 2 LAST CDS_SEC 1
J 2
(-775 650);
DISPLAY 0.680851 (-775 650);
DISPLAY INVISIBLE (-775 650);
FORCEPROP 2 LASTPIN (-875 575) $PN 1
J 0
(-865 585);
DISPLAY 0.808511 (-865 585);
FORCEPROP 2 LASTPIN (-1025 575) $PN 2
J 2
(-1035 585);
DISPLAY 0.808511 (-1035 585);
FORCEPROP 2 LAST VALUE DIFF BUS_0.22UF
J 2
(-1100 575);
DISPLAY 0.553191 (-1100 575);
FORCEPROP 1 LAST PIN_NAMES_ROTATE TRUE
J 2
(-950 575);
DISPLAY 0.489362 (-950 575);
PAINT GREEN (-950 575);
DISPLAY INVISIBLE (-950 575);
FORCEPROP 2 LAST CDS_LIB pure_quanta
J 2
(-950 575);
DISPLAY INVISIBLE (-950 575);
FORCEPROP 1 LAST CDS_LMAN_SYM_OUTLINE -25,50,25,-50
J 2
(-950 575);
DISPLAY 0.468085 (-950 575);
PAINT GREEN (-950 575);
DISPLAY INVISIBLE (-950 575);
FORCEPROP 2 LAST VOLTAGE 6.3V
J 2
(-1300 625);
DISPLAY 0.553191 (-1300 625);
DISPLAY INVISIBLE (-1300 625);
FORCEPROP 1 LAST MATERIAL X6S
J 2
(-941 654);
DISPLAY 0.574468 (-941 654);
PAINT GREEN (-941 654);
DISPLAY INVISIBLE (-941 654);
FORCEPROP 2 LAST PACK_TYPE C0201
J 2
(-1125 625);
DISPLAY 0.553191 (-1125 625);
DISPLAY INVISIBLE (-1125 625);
FORCEPROP 2 LAST TOLERANCE 20%
J 2
(-1025 625);
DISPLAY 0.553191 (-1025 625);
DISPLAY INVISIBLE (-1025 625);
FORCEPROP 1 LAST PART_NUMBER SP_CH4221MEE01
J 2
(-1066 663);
DISPLAY 0.574468 (-1066 663);
PAINT GREEN (-1066 663);
DISPLAY INVISIBLE (-1066 663);
FORCEPROP 1 LAST LOCATION C737
J 0
(-700 650);
DISPLAY 1.021277 (-700 650);
DISPLAY INVISIBLE (-700 650);
FORCEPROP 1 LAST PATH I233
J 2
(-950 575);
DISPLAY 0.723404 (-950 575);
DISPLAY INVISIBLE (-950 575);
FORCEADD Q_CAP_DIFFBUS..2
R 2
(-950 625);
FORCEPROP 1 LAST LOCATION C736
J 2
(-716 642);
DISPLAY 0.723404 (-716 642);
PAINT GREEN (-716 642);
FORCEPROP 2 LAST $SEC 1
J 2
(-775 700);
DISPLAY 0.680851 (-775 700);
PAINT MONO (-775 700);
DISPLAY INVISIBLE (-775 700);
FORCEPROP 2 LAST CDS_SEC 1
J 2
(-775 700);
DISPLAY 0.680851 (-775 700);
DISPLAY INVISIBLE (-775 700);
FORCEPROP 2 LASTPIN (-875 625) $PN 1
J 0
(-865 635);
DISPLAY 0.808511 (-865 635);
FORCEPROP 2 LASTPIN (-1025 625) $PN 2
J 2
(-1035 635);
DISPLAY 0.808511 (-1035 635);
FORCEPROP 2 LAST VALUE DIFF BUS_0.22UF
J 2
(-1100 625);
DISPLAY 0.553191 (-1100 625);
FORCEPROP 1 LAST PIN_NAMES_ROTATE TRUE
J 2
(-950 625);
DISPLAY 0.489362 (-950 625);
PAINT GREEN (-950 625);
DISPLAY INVISIBLE (-950 625);
FORCEPROP 2 LAST CDS_LIB pure_quanta
J 2
(-950 625);
DISPLAY INVISIBLE (-950 625);
FORCEPROP 1 LAST CDS_LMAN_SYM_OUTLINE -25,50,25,-50
J 2
(-950 625);
DISPLAY 0.468085 (-950 625);
PAINT GREEN (-950 625);
DISPLAY INVISIBLE (-950 625);
FORCEPROP 2 LAST VOLTAGE 6.3V
J 2
(-1300 675);
DISPLAY 0.553191 (-1300 675);
DISPLAY INVISIBLE (-1300 675);
FORCEPROP 1 LAST MATERIAL X6S
J 2
(-941 704);
DISPLAY 0.574468 (-941 704);
PAINT GREEN (-941 704);
DISPLAY INVISIBLE (-941 704);
FORCEPROP 2 LAST PACK_TYPE C0201
J 2
(-1125 675);
DISPLAY 0.553191 (-1125 675);
DISPLAY INVISIBLE (-1125 675);
FORCEPROP 2 LAST TOLERANCE 20%
J 2
(-1025 675);
DISPLAY 0.553191 (-1025 675);
DISPLAY INVISIBLE (-1025 675);
FORCEPROP 1 LAST PART_NUMBER SP_CH4221MEE01
J 2
(-1066 713);
DISPLAY 0.574468 (-1066 713);
PAINT GREEN (-1066 713);
DISPLAY INVISIBLE (-1066 713);
FORCEPROP 1 LAST LOCATION C736
J 0
(-700 700);
DISPLAY 1.021277 (-700 700);
DISPLAY INVISIBLE (-700 700);
FORCEPROP 1 LAST PATH I234
J 2
(-950 625);
DISPLAY 0.723404 (-950 625);
DISPLAY INVISIBLE (-950 625);
FORCEADD Q_CAP_DIFFBUS..2
R 2
(-950 825);
FORCEPROP 1 LAST LOCATION C734
J 2
(-716 842);
DISPLAY 0.723404 (-716 842);
PAINT GREEN (-716 842);
FORCEPROP 2 LAST $SEC 1
J 2
(-775 900);
DISPLAY 0.680851 (-775 900);
PAINT MONO (-775 900);
DISPLAY INVISIBLE (-775 900);
FORCEPROP 2 LAST CDS_SEC 1
J 2
(-775 900);
DISPLAY 0.680851 (-775 900);
DISPLAY INVISIBLE (-775 900);
FORCEPROP 2 LASTPIN (-875 825) $PN 1
J 0
(-865 835);
DISPLAY 0.808511 (-865 835);
FORCEPROP 2 LASTPIN (-1025 825) $PN 2
J 2
(-1035 835);
DISPLAY 0.808511 (-1035 835);
FORCEPROP 2 LAST VALUE DIFF BUS_0.22UF
J 2
(-1100 825);
DISPLAY 0.553191 (-1100 825);
FORCEPROP 1 LAST PIN_NAMES_ROTATE TRUE
J 2
(-950 825);
DISPLAY 0.489362 (-950 825);
PAINT GREEN (-950 825);
DISPLAY INVISIBLE (-950 825);
FORCEPROP 1 LAST CDS_LMAN_SYM_OUTLINE -25,50,25,-50
J 2
(-950 825);
DISPLAY 0.468085 (-950 825);
PAINT GREEN (-950 825);
DISPLAY INVISIBLE (-950 825);
FORCEPROP 2 LAST CDS_LIB pure_quanta
J 2
(-950 825);
DISPLAY INVISIBLE (-950 825);
FORCEPROP 2 LAST VOLTAGE 6.3V
J 2
(-1300 875);
DISPLAY 0.553191 (-1300 875);
DISPLAY INVISIBLE (-1300 875);
FORCEPROP 1 LAST MATERIAL X6S
J 2
(-941 904);
DISPLAY 0.574468 (-941 904);
PAINT GREEN (-941 904);
DISPLAY INVISIBLE (-941 904);
FORCEPROP 2 LAST PACK_TYPE C0201
J 2
(-1125 875);
DISPLAY 0.553191 (-1125 875);
DISPLAY INVISIBLE (-1125 875);
FORCEPROP 2 LAST TOLERANCE 20%
J 2
(-1025 875);
DISPLAY 0.553191 (-1025 875);
DISPLAY INVISIBLE (-1025 875);
FORCEPROP 1 LAST PART_NUMBER SP_CH4221MEE01
J 2
(-1066 913);
DISPLAY 0.574468 (-1066 913);
PAINT GREEN (-1066 913);
DISPLAY INVISIBLE (-1066 913);
FORCEPROP 1 LAST LOCATION C734
J 0
(-700 900);
DISPLAY 1.021277 (-700 900);
DISPLAY INVISIBLE (-700 900);
FORCEPROP 1 LAST PATH I235
J 2
(-950 825);
DISPLAY 0.723404 (-950 825);
DISPLAY INVISIBLE (-950 825);
FORCEADD Q_CAP_DIFFBUS..2
R 2
(-950 775);
FORCEPROP 1 LAST LOCATION C735
J 2
(-716 792);
DISPLAY 0.723404 (-716 792);
PAINT GREEN (-716 792);
FORCEPROP 2 LAST $SEC 1
J 2
(-775 850);
DISPLAY 0.680851 (-775 850);
PAINT MONO (-775 850);
DISPLAY INVISIBLE (-775 850);
FORCEPROP 2 LAST CDS_SEC 1
J 2
(-775 850);
DISPLAY 0.680851 (-775 850);
DISPLAY INVISIBLE (-775 850);
FORCEPROP 2 LASTPIN (-875 775) $PN 1
J 0
(-865 785);
DISPLAY 0.808511 (-865 785);
FORCEPROP 2 LASTPIN (-1025 775) $PN 2
J 2
(-1035 785);
DISPLAY 0.808511 (-1035 785);
FORCEPROP 2 LAST VALUE DIFF BUS_0.22UF
J 2
(-1100 775);
DISPLAY 0.553191 (-1100 775);
FORCEPROP 1 LAST PIN_NAMES_ROTATE TRUE
J 2
(-950 775);
DISPLAY 0.489362 (-950 775);
PAINT GREEN (-950 775);
DISPLAY INVISIBLE (-950 775);
FORCEPROP 1 LAST CDS_LMAN_SYM_OUTLINE -25,50,25,-50
J 2
(-950 775);
DISPLAY 0.468085 (-950 775);
PAINT GREEN (-950 775);
DISPLAY INVISIBLE (-950 775);
FORCEPROP 2 LAST CDS_LIB pure_quanta
J 2
(-950 775);
DISPLAY INVISIBLE (-950 775);
FORCEPROP 2 LAST VOLTAGE 6.3V
J 2
(-1300 825);
DISPLAY 0.553191 (-1300 825);
DISPLAY INVISIBLE (-1300 825);
FORCEPROP 1 LAST MATERIAL X6S
J 2
(-941 854);
DISPLAY 0.574468 (-941 854);
PAINT GREEN (-941 854);
DISPLAY INVISIBLE (-941 854);
FORCEPROP 2 LAST PACK_TYPE C0201
J 2
(-1125 825);
DISPLAY 0.553191 (-1125 825);
DISPLAY INVISIBLE (-1125 825);
FORCEPROP 2 LAST TOLERANCE 20%
J 2
(-1025 825);
DISPLAY 0.553191 (-1025 825);
DISPLAY INVISIBLE (-1025 825);
FORCEPROP 1 LAST PART_NUMBER SP_CH4221MEE01
J 2
(-1066 863);
DISPLAY 0.574468 (-1066 863);
PAINT GREEN (-1066 863);
DISPLAY INVISIBLE (-1066 863);
FORCEPROP 1 LAST LOCATION C735
J 0
(-700 850);
DISPLAY 1.021277 (-700 850);
DISPLAY INVISIBLE (-700 850);
FORCEPROP 1 LAST PATH I236
J 2
(-950 775);
DISPLAY 0.723404 (-950 775);
DISPLAY INVISIBLE (-950 775);
FORCEADD Q_CAP_DIFFBUS..2
R 2
(-950 975);
FORCEPROP 1 LAST LOCATION C733
J 2
(-716 992);
DISPLAY 0.723404 (-716 992);
PAINT GREEN (-716 992);
FORCEPROP 2 LAST $SEC 1
J 2
(-775 1050);
DISPLAY 0.680851 (-775 1050);
PAINT MONO (-775 1050);
DISPLAY INVISIBLE (-775 1050);
FORCEPROP 2 LAST CDS_SEC 1
J 2
(-775 1050);
DISPLAY 0.680851 (-775 1050);
DISPLAY INVISIBLE (-775 1050);
FORCEPROP 2 LASTPIN (-875 975) $PN 1
J 0
(-865 985);
DISPLAY 0.808511 (-865 985);
FORCEPROP 2 LASTPIN (-1025 975) $PN 2
J 2
(-1035 985);
DISPLAY 0.808511 (-1035 985);
FORCEPROP 2 LAST VALUE DIFF BUS_0.22UF
J 2
(-1100 975);
DISPLAY 0.553191 (-1100 975);
FORCEPROP 1 LAST PIN_NAMES_ROTATE TRUE
J 2
(-950 975);
DISPLAY 0.489362 (-950 975);
PAINT GREEN (-950 975);
DISPLAY INVISIBLE (-950 975);
FORCEPROP 2 LAST CDS_LIB pure_quanta
J 2
(-950 975);
DISPLAY INVISIBLE (-950 975);
FORCEPROP 1 LAST CDS_LMAN_SYM_OUTLINE -25,50,25,-50
J 2
(-950 975);
DISPLAY 0.468085 (-950 975);
PAINT GREEN (-950 975);
DISPLAY INVISIBLE (-950 975);
FORCEPROP 2 LAST VOLTAGE 6.3V
J 2
(-1300 1025);
DISPLAY 0.553191 (-1300 1025);
DISPLAY INVISIBLE (-1300 1025);
FORCEPROP 1 LAST MATERIAL X6S
J 2
(-941 1054);
DISPLAY 0.574468 (-941 1054);
PAINT GREEN (-941 1054);
DISPLAY INVISIBLE (-941 1054);
FORCEPROP 2 LAST PACK_TYPE C0201
J 2
(-1125 1025);
DISPLAY 0.553191 (-1125 1025);
DISPLAY INVISIBLE (-1125 1025);
FORCEPROP 2 LAST TOLERANCE 20%
J 2
(-1025 1025);
DISPLAY 0.553191 (-1025 1025);
DISPLAY INVISIBLE (-1025 1025);
FORCEPROP 1 LAST PART_NUMBER SP_CH4221MEE01
J 2
(-1066 1063);
DISPLAY 0.574468 (-1066 1063);
PAINT GREEN (-1066 1063);
DISPLAY INVISIBLE (-1066 1063);
FORCEPROP 1 LAST LOCATION C733
J 0
(-700 1050);
DISPLAY 1.021277 (-700 1050);
DISPLAY INVISIBLE (-700 1050);
FORCEPROP 1 LAST PATH I237
J 2
(-950 975);
DISPLAY 0.723404 (-950 975);
DISPLAY INVISIBLE (-950 975);
FORCEADD TAP..1
(-400 225);
FORCEPROP 3 LASTPIN (-450 225) SIG_NAME P5E_CPU1_P1_TX_C_DN<0>
J 0
(-440 235);
DISPLAY 0.659574 (-440 235);
PAINT MONO (-440 235);
DISPLAY INVISIBLE (-440 235);
FORCEPROP 1 LASTPIN (-450 225) BN 0
J 0
(-462 233);
DISPLAY 0.680851 (-462 233);
PAINT GREEN (-462 233);
FORCEPROP 2 LAST CDS_LIB standard
J 0
(-400 225);
DISPLAY INVISIBLE (-400 225);
FORCEPROP 1 LAST BODY_TYPE PLUMBING
J 0
(-400 275);
DISPLAY 0.872340 (-400 275);
PAINT GREEN (-400 275);
DISPLAY INVISIBLE (-400 275);
FORCEPROP 1 LAST HDL_TAP TRUE
J 0
(-75 100);
DISPLAY 0.872340 (-75 100);
DISPLAY INVISIBLE (-75 100);
FORCEPROP 1 LAST PATH I238
J 0
(-402 225);
DISPLAY 0.872340 (-402 225);
PAINT GREEN (-402 225);
DISPLAY INVISIBLE (-402 225);
FORCEADD TAP..1
(-400 425);
FORCEPROP 3 LASTPIN (-450 425) SIG_NAME P5E_CPU1_P1_TX_C_DN<1>
J 0
(-440 435);
DISPLAY 0.659574 (-440 435);
PAINT MONO (-440 435);
DISPLAY INVISIBLE (-440 435);
FORCEPROP 1 LASTPIN (-450 425) BN 1
J 0
(-462 433);
DISPLAY 0.680851 (-462 433);
PAINT GREEN (-462 433);
FORCEPROP 2 LAST CDS_LIB standard
J 0
(-400 425);
DISPLAY INVISIBLE (-400 425);
FORCEPROP 1 LAST BODY_TYPE PLUMBING
J 0
(-400 475);
DISPLAY 0.872340 (-400 475);
PAINT GREEN (-400 475);
DISPLAY INVISIBLE (-400 475);
FORCEPROP 1 LAST HDL_TAP TRUE
J 0
(-75 300);
DISPLAY 0.872340 (-75 300);
DISPLAY INVISIBLE (-75 300);
FORCEPROP 1 LAST PATH I239
J 0
(-402 425);
DISPLAY 0.872340 (-402 425);
PAINT GREEN (-402 425);
DISPLAY INVISIBLE (-402 425);
FORCEADD TAP..1
(-200 175);
FORCEPROP 3 LASTPIN (-250 175) SIG_NAME P5E_CPU1_P1_TX_C_DP<0>
J 0
(-240 185);
DISPLAY 0.659574 (-240 185);
PAINT MONO (-240 185);
DISPLAY INVISIBLE (-240 185);
FORCEPROP 1 LASTPIN (-250 175) BN 0
J 0
(-262 183);
DISPLAY 0.680851 (-262 183);
PAINT GREEN (-262 183);
FORCEPROP 2 LAST CDS_LIB standard
J 0
(-200 175);
DISPLAY INVISIBLE (-200 175);
FORCEPROP 1 LAST BODY_TYPE PLUMBING
J 0
(-200 225);
DISPLAY 0.872340 (-200 225);
PAINT GREEN (-200 225);
DISPLAY INVISIBLE (-200 225);
FORCEPROP 1 LAST HDL_TAP TRUE
J 0
(125 50);
DISPLAY 0.872340 (125 50);
DISPLAY INVISIBLE (125 50);
FORCEPROP 1 LAST PATH I240
J 0
(-202 175);
DISPLAY 0.872340 (-202 175);
PAINT GREEN (-202 175);
DISPLAY INVISIBLE (-202 175);
FORCEADD TAP..1
(-200 375);
FORCEPROP 3 LASTPIN (-250 375) SIG_NAME P5E_CPU1_P1_TX_C_DP<1>
J 0
(-240 385);
DISPLAY 0.659574 (-240 385);
PAINT MONO (-240 385);
DISPLAY INVISIBLE (-240 385);
FORCEPROP 1 LASTPIN (-250 375) BN 1
J 0
(-262 383);
DISPLAY 0.680851 (-262 383);
PAINT GREEN (-262 383);
FORCEPROP 2 LAST CDS_LIB standard
J 0
(-200 375);
DISPLAY INVISIBLE (-200 375);
FORCEPROP 1 LAST BODY_TYPE PLUMBING
J 0
(-200 425);
DISPLAY 0.872340 (-200 425);
PAINT GREEN (-200 425);
DISPLAY INVISIBLE (-200 425);
FORCEPROP 1 LAST HDL_TAP TRUE
J 0
(125 250);
DISPLAY 0.872340 (125 250);
DISPLAY INVISIBLE (125 250);
FORCEPROP 1 LAST PATH I241
J 0
(-202 375);
DISPLAY 0.872340 (-202 375);
PAINT GREEN (-202 375);
DISPLAY INVISIBLE (-202 375);
FORCEADD TAP..1
(-400 625);
FORCEPROP 3 LASTPIN (-450 625) SIG_NAME P5E_CPU1_P1_TX_C_DN<2>
J 0
(-440 635);
DISPLAY 0.659574 (-440 635);
PAINT MONO (-440 635);
DISPLAY INVISIBLE (-440 635);
FORCEPROP 1 LASTPIN (-450 625) BN 2
J 0
(-462 633);
DISPLAY 0.680851 (-462 633);
PAINT GREEN (-462 633);
FORCEPROP 2 LAST CDS_LIB standard
J 0
(-400 625);
DISPLAY INVISIBLE (-400 625);
FORCEPROP 1 LAST BODY_TYPE PLUMBING
J 0
(-400 675);
DISPLAY 0.872340 (-400 675);
PAINT GREEN (-400 675);
DISPLAY INVISIBLE (-400 675);
FORCEPROP 1 LAST HDL_TAP TRUE
J 0
(-75 500);
DISPLAY 0.872340 (-75 500);
DISPLAY INVISIBLE (-75 500);
FORCEPROP 1 LAST PATH I242
J 0
(-402 625);
DISPLAY 0.872340 (-402 625);
PAINT GREEN (-402 625);
DISPLAY INVISIBLE (-402 625);
FORCEADD TAP..1
(-400 825);
FORCEPROP 3 LASTPIN (-450 825) SIG_NAME P5E_CPU1_P1_TX_C_DN<3>
J 0
(-440 835);
DISPLAY 0.659574 (-440 835);
PAINT MONO (-440 835);
DISPLAY INVISIBLE (-440 835);
FORCEPROP 1 LASTPIN (-450 825) BN 3
J 0
(-462 833);
DISPLAY 0.680851 (-462 833);
PAINT GREEN (-462 833);
FORCEPROP 2 LAST CDS_LIB standard
J 0
(-400 825);
DISPLAY INVISIBLE (-400 825);
FORCEPROP 1 LAST BODY_TYPE PLUMBING
J 0
(-400 875);
DISPLAY 0.872340 (-400 875);
PAINT GREEN (-400 875);
DISPLAY INVISIBLE (-400 875);
FORCEPROP 1 LAST HDL_TAP TRUE
J 0
(-75 700);
DISPLAY 0.872340 (-75 700);
DISPLAY INVISIBLE (-75 700);
FORCEPROP 1 LAST PATH I243
J 0
(-402 825);
DISPLAY 0.872340 (-402 825);
PAINT GREEN (-402 825);
DISPLAY INVISIBLE (-402 825);
FORCEADD TAP..1
(-200 575);
FORCEPROP 3 LASTPIN (-250 575) SIG_NAME P5E_CPU1_P1_TX_C_DP<2>
J 0
(-240 585);
DISPLAY 0.659574 (-240 585);
PAINT MONO (-240 585);
DISPLAY INVISIBLE (-240 585);
FORCEPROP 1 LASTPIN (-250 575) BN 2
J 0
(-262 583);
DISPLAY 0.680851 (-262 583);
PAINT GREEN (-262 583);
FORCEPROP 2 LAST CDS_LIB standard
J 0
(-200 575);
DISPLAY INVISIBLE (-200 575);
FORCEPROP 1 LAST BODY_TYPE PLUMBING
J 0
(-200 625);
DISPLAY 0.872340 (-200 625);
PAINT GREEN (-200 625);
DISPLAY INVISIBLE (-200 625);
FORCEPROP 1 LAST HDL_TAP TRUE
J 0
(125 450);
DISPLAY 0.872340 (125 450);
DISPLAY INVISIBLE (125 450);
FORCEPROP 1 LAST PATH I244
J 0
(-202 575);
DISPLAY 0.872340 (-202 575);
PAINT GREEN (-202 575);
DISPLAY INVISIBLE (-202 575);
FORCEADD TAP..1
(-200 775);
FORCEPROP 3 LASTPIN (-250 775) SIG_NAME P5E_CPU1_P1_TX_C_DP<3>
J 0
(-240 785);
DISPLAY 0.659574 (-240 785);
PAINT MONO (-240 785);
DISPLAY INVISIBLE (-240 785);
FORCEPROP 1 LASTPIN (-250 775) BN 3
J 0
(-262 783);
DISPLAY 0.680851 (-262 783);
PAINT GREEN (-262 783);
FORCEPROP 2 LAST CDS_LIB standard
J 0
(-200 775);
DISPLAY INVISIBLE (-200 775);
FORCEPROP 1 LAST BODY_TYPE PLUMBING
J 0
(-200 825);
DISPLAY 0.872340 (-200 825);
PAINT GREEN (-200 825);
DISPLAY INVISIBLE (-200 825);
FORCEPROP 1 LAST HDL_TAP TRUE
J 0
(125 650);
DISPLAY 0.872340 (125 650);
DISPLAY INVISIBLE (125 650);
FORCEPROP 1 LAST PATH I245
J 0
(-202 775);
DISPLAY 0.872340 (-202 775);
PAINT GREEN (-202 775);
DISPLAY INVISIBLE (-202 775);
FORCEADD Q_CAP_DIFFBUS..2
R 2
(-950 1025);
FORCEPROP 1 LAST LOCATION C732
J 2
(-716 1042);
DISPLAY 0.723404 (-716 1042);
PAINT GREEN (-716 1042);
FORCEPROP 2 LAST $SEC 1
J 2
(-775 1100);
DISPLAY 0.680851 (-775 1100);
PAINT MONO (-775 1100);
DISPLAY INVISIBLE (-775 1100);
FORCEPROP 2 LAST CDS_SEC 1
J 2
(-775 1100);
DISPLAY 0.680851 (-775 1100);
DISPLAY INVISIBLE (-775 1100);
FORCEPROP 2 LASTPIN (-875 1025) $PN 1
J 0
(-865 1035);
DISPLAY 0.808511 (-865 1035);
FORCEPROP 2 LASTPIN (-1025 1025) $PN 2
J 2
(-1035 1035);
DISPLAY 0.808511 (-1035 1035);
FORCEPROP 2 LAST VALUE DIFF BUS_0.22UF
J 2
(-1100 1025);
DISPLAY 0.553191 (-1100 1025);
FORCEPROP 1 LAST PIN_NAMES_ROTATE TRUE
J 2
(-950 1025);
DISPLAY 0.489362 (-950 1025);
PAINT GREEN (-950 1025);
DISPLAY INVISIBLE (-950 1025);
FORCEPROP 2 LAST CDS_LIB pure_quanta
J 2
(-950 1025);
DISPLAY INVISIBLE (-950 1025);
FORCEPROP 1 LAST CDS_LMAN_SYM_OUTLINE -25,50,25,-50
J 2
(-950 1025);
DISPLAY 0.468085 (-950 1025);
PAINT GREEN (-950 1025);
DISPLAY INVISIBLE (-950 1025);
FORCEPROP 2 LAST VOLTAGE 6.3V
J 2
(-1300 1075);
DISPLAY 0.553191 (-1300 1075);
DISPLAY INVISIBLE (-1300 1075);
FORCEPROP 1 LAST MATERIAL X6S
J 2
(-941 1104);
DISPLAY 0.574468 (-941 1104);
PAINT GREEN (-941 1104);
DISPLAY INVISIBLE (-941 1104);
FORCEPROP 2 LAST PACK_TYPE C0201
J 2
(-1125 1075);
DISPLAY 0.553191 (-1125 1075);
DISPLAY INVISIBLE (-1125 1075);
FORCEPROP 2 LAST TOLERANCE 20%
J 2
(-1025 1075);
DISPLAY 0.553191 (-1025 1075);
DISPLAY INVISIBLE (-1025 1075);
FORCEPROP 1 LAST PART_NUMBER SP_CH4221MEE01
J 2
(-1066 1113);
DISPLAY 0.574468 (-1066 1113);
PAINT GREEN (-1066 1113);
DISPLAY INVISIBLE (-1066 1113);
FORCEPROP 1 LAST LOCATION C732
J 0
(-700 1100);
DISPLAY 1.021277 (-700 1100);
DISPLAY INVISIBLE (-700 1100);
FORCEPROP 1 LAST PATH I246
J 2
(-950 1025);
DISPLAY 0.723404 (-950 1025);
DISPLAY INVISIBLE (-950 1025);
FORCEADD Q_CAP_DIFFBUS..2
R 2
(-950 1175);
FORCEPROP 1 LAST LOCATION C731
J 2
(-716 1192);
DISPLAY 0.723404 (-716 1192);
PAINT GREEN (-716 1192);
FORCEPROP 2 LAST $SEC 1
J 2
(-775 1250);
DISPLAY 0.680851 (-775 1250);
PAINT MONO (-775 1250);
DISPLAY INVISIBLE (-775 1250);
FORCEPROP 2 LAST CDS_SEC 1
J 2
(-775 1250);
DISPLAY 0.680851 (-775 1250);
DISPLAY INVISIBLE (-775 1250);
FORCEPROP 2 LASTPIN (-875 1175) $PN 1
J 0
(-865 1185);
DISPLAY 0.808511 (-865 1185);
FORCEPROP 2 LASTPIN (-1025 1175) $PN 2
J 2
(-1035 1185);
DISPLAY 0.808511 (-1035 1185);
FORCEPROP 2 LAST VALUE DIFF BUS_0.22UF
J 2
(-1100 1175);
DISPLAY 0.553191 (-1100 1175);
FORCEPROP 1 LAST PIN_NAMES_ROTATE TRUE
J 2
(-950 1175);
DISPLAY 0.489362 (-950 1175);
PAINT GREEN (-950 1175);
DISPLAY INVISIBLE (-950 1175);
FORCEPROP 2 LAST CDS_LIB pure_quanta
J 2
(-950 1175);
DISPLAY INVISIBLE (-950 1175);
FORCEPROP 1 LAST CDS_LMAN_SYM_OUTLINE -25,50,25,-50
J 2
(-950 1175);
DISPLAY 0.468085 (-950 1175);
PAINT GREEN (-950 1175);
DISPLAY INVISIBLE (-950 1175);
FORCEPROP 2 LAST VOLTAGE 6.3V
J 2
(-1300 1225);
DISPLAY 0.553191 (-1300 1225);
DISPLAY INVISIBLE (-1300 1225);
FORCEPROP 1 LAST MATERIAL X6S
J 2
(-941 1254);
DISPLAY 0.574468 (-941 1254);
PAINT GREEN (-941 1254);
DISPLAY INVISIBLE (-941 1254);
FORCEPROP 2 LAST PACK_TYPE C0201
J 2
(-1125 1225);
DISPLAY 0.553191 (-1125 1225);
DISPLAY INVISIBLE (-1125 1225);
FORCEPROP 2 LAST TOLERANCE 20%
J 2
(-1025 1225);
DISPLAY 0.553191 (-1025 1225);
DISPLAY INVISIBLE (-1025 1225);
FORCEPROP 1 LAST PART_NUMBER SP_CH4221MEE01
J 2
(-1066 1263);
DISPLAY 0.574468 (-1066 1263);
PAINT GREEN (-1066 1263);
DISPLAY INVISIBLE (-1066 1263);
FORCEPROP 1 LAST LOCATION C731
J 0
(-700 1250);
DISPLAY 1.021277 (-700 1250);
DISPLAY INVISIBLE (-700 1250);
FORCEPROP 1 LAST PATH I247
J 2
(-950 1175);
DISPLAY 0.723404 (-950 1175);
DISPLAY INVISIBLE (-950 1175);
FORCEADD Q_CAP_DIFFBUS..2
R 2
(-950 1225);
FORCEPROP 1 LAST LOCATION C730
J 2
(-716 1242);
DISPLAY 0.723404 (-716 1242);
PAINT GREEN (-716 1242);
FORCEPROP 2 LAST $SEC 1
J 2
(-775 1300);
DISPLAY 0.680851 (-775 1300);
PAINT MONO (-775 1300);
DISPLAY INVISIBLE (-775 1300);
FORCEPROP 2 LAST CDS_SEC 1
J 2
(-775 1300);
DISPLAY 0.680851 (-775 1300);
DISPLAY INVISIBLE (-775 1300);
FORCEPROP 2 LASTPIN (-875 1225) $PN 1
J 0
(-865 1235);
DISPLAY 0.808511 (-865 1235);
FORCEPROP 2 LASTPIN (-1025 1225) $PN 2
J 2
(-1035 1235);
DISPLAY 0.808511 (-1035 1235);
FORCEPROP 2 LAST VALUE DIFF BUS_0.22UF
J 2
(-1100 1225);
DISPLAY 0.553191 (-1100 1225);
FORCEPROP 1 LAST PIN_NAMES_ROTATE TRUE
J 2
(-950 1225);
DISPLAY 0.489362 (-950 1225);
PAINT GREEN (-950 1225);
DISPLAY INVISIBLE (-950 1225);
FORCEPROP 2 LAST CDS_LIB pure_quanta
J 2
(-950 1225);
DISPLAY INVISIBLE (-950 1225);
FORCEPROP 1 LAST CDS_LMAN_SYM_OUTLINE -25,50,25,-50
J 2
(-950 1225);
DISPLAY 0.468085 (-950 1225);
PAINT GREEN (-950 1225);
DISPLAY INVISIBLE (-950 1225);
FORCEPROP 2 LAST VOLTAGE 6.3V
J 2
(-1300 1275);
DISPLAY 0.553191 (-1300 1275);
DISPLAY INVISIBLE (-1300 1275);
FORCEPROP 1 LAST MATERIAL X6S
J 2
(-941 1304);
DISPLAY 0.574468 (-941 1304);
PAINT GREEN (-941 1304);
DISPLAY INVISIBLE (-941 1304);
FORCEPROP 2 LAST PACK_TYPE C0201
J 2
(-1125 1275);
DISPLAY 0.553191 (-1125 1275);
DISPLAY INVISIBLE (-1125 1275);
FORCEPROP 2 LAST TOLERANCE 20%
J 2
(-1025 1275);
DISPLAY 0.553191 (-1025 1275);
DISPLAY INVISIBLE (-1025 1275);
FORCEPROP 1 LAST PART_NUMBER SP_CH4221MEE01
J 2
(-1066 1313);
DISPLAY 0.574468 (-1066 1313);
PAINT GREEN (-1066 1313);
DISPLAY INVISIBLE (-1066 1313);
FORCEPROP 1 LAST LOCATION C730
J 0
(-700 1300);
DISPLAY 1.021277 (-700 1300);
DISPLAY INVISIBLE (-700 1300);
FORCEPROP 1 LAST PATH I248
J 2
(-950 1225);
DISPLAY 0.723404 (-950 1225);
DISPLAY INVISIBLE (-950 1225);
FORCEADD Q_CAP_DIFFBUS..2
R 2
(-950 1375);
FORCEPROP 1 LAST LOCATION C729
J 2
(-716 1392);
DISPLAY 0.723404 (-716 1392);
PAINT GREEN (-716 1392);
FORCEPROP 2 LAST $SEC 1
J 2
(-775 1450);
DISPLAY 0.680851 (-775 1450);
PAINT MONO (-775 1450);
DISPLAY INVISIBLE (-775 1450);
FORCEPROP 2 LAST CDS_SEC 1
J 2
(-775 1450);
DISPLAY 0.680851 (-775 1450);
DISPLAY INVISIBLE (-775 1450);
FORCEPROP 2 LASTPIN (-875 1375) $PN 1
J 0
(-865 1385);
DISPLAY 0.808511 (-865 1385);
FORCEPROP 2 LASTPIN (-1025 1375) $PN 2
J 2
(-1035 1385);
DISPLAY 0.808511 (-1035 1385);
FORCEPROP 2 LAST VALUE DIFF BUS_0.22UF
J 2
(-1100 1375);
DISPLAY 0.553191 (-1100 1375);
FORCEPROP 1 LAST PIN_NAMES_ROTATE TRUE
J 2
(-950 1375);
DISPLAY 0.489362 (-950 1375);
PAINT GREEN (-950 1375);
DISPLAY INVISIBLE (-950 1375);
FORCEPROP 2 LAST CDS_LIB pure_quanta
J 2
(-950 1375);
DISPLAY INVISIBLE (-950 1375);
FORCEPROP 1 LAST CDS_LMAN_SYM_OUTLINE -25,50,25,-50
J 2
(-950 1375);
DISPLAY 0.468085 (-950 1375);
PAINT GREEN (-950 1375);
DISPLAY INVISIBLE (-950 1375);
FORCEPROP 2 LAST VOLTAGE 6.3V
J 2
(-1300 1425);
DISPLAY 0.553191 (-1300 1425);
DISPLAY INVISIBLE (-1300 1425);
FORCEPROP 1 LAST MATERIAL X6S
J 2
(-941 1454);
DISPLAY 0.574468 (-941 1454);
PAINT GREEN (-941 1454);
DISPLAY INVISIBLE (-941 1454);
FORCEPROP 2 LAST PACK_TYPE C0201
J 2
(-1125 1425);
DISPLAY 0.553191 (-1125 1425);
DISPLAY INVISIBLE (-1125 1425);
FORCEPROP 2 LAST TOLERANCE 20%
J 2
(-1025 1425);
DISPLAY 0.553191 (-1025 1425);
DISPLAY INVISIBLE (-1025 1425);
FORCEPROP 1 LAST PART_NUMBER SP_CH4221MEE01
J 2
(-1066 1463);
DISPLAY 0.574468 (-1066 1463);
PAINT GREEN (-1066 1463);
DISPLAY INVISIBLE (-1066 1463);
FORCEPROP 1 LAST LOCATION C729
J 0
(-700 1450);
DISPLAY 1.021277 (-700 1450);
DISPLAY INVISIBLE (-700 1450);
FORCEPROP 1 LAST PATH I249
J 2
(-950 1375);
DISPLAY 0.723404 (-950 1375);
DISPLAY INVISIBLE (-950 1375);
FORCEADD Q_CAP_DIFFBUS..2
R 2
(-950 1425);
FORCEPROP 1 LAST LOCATION C728
J 2
(-716 1442);
DISPLAY 0.723404 (-716 1442);
PAINT GREEN (-716 1442);
FORCEPROP 2 LAST $SEC 1
J 2
(-775 1500);
DISPLAY 0.680851 (-775 1500);
PAINT MONO (-775 1500);
DISPLAY INVISIBLE (-775 1500);
FORCEPROP 2 LAST CDS_SEC 1
J 2
(-775 1500);
DISPLAY 0.680851 (-775 1500);
DISPLAY INVISIBLE (-775 1500);
FORCEPROP 2 LASTPIN (-875 1425) $PN 1
J 0
(-865 1435);
DISPLAY 0.808511 (-865 1435);
FORCEPROP 2 LASTPIN (-1025 1425) $PN 2
J 2
(-1035 1435);
DISPLAY 0.808511 (-1035 1435);
FORCEPROP 2 LAST VALUE DIFF BUS_0.22UF
J 2
(-1100 1425);
DISPLAY 0.553191 (-1100 1425);
FORCEPROP 1 LAST PIN_NAMES_ROTATE TRUE
J 2
(-950 1425);
DISPLAY 0.489362 (-950 1425);
PAINT GREEN (-950 1425);
DISPLAY INVISIBLE (-950 1425);
FORCEPROP 2 LAST CDS_LIB pure_quanta
J 2
(-950 1425);
DISPLAY INVISIBLE (-950 1425);
FORCEPROP 1 LAST CDS_LMAN_SYM_OUTLINE -25,50,25,-50
J 2
(-950 1425);
DISPLAY 0.468085 (-950 1425);
PAINT GREEN (-950 1425);
DISPLAY INVISIBLE (-950 1425);
FORCEPROP 2 LAST VOLTAGE 6.3V
J 2
(-1300 1475);
DISPLAY 0.553191 (-1300 1475);
DISPLAY INVISIBLE (-1300 1475);
FORCEPROP 1 LAST MATERIAL X6S
J 2
(-941 1504);
DISPLAY 0.574468 (-941 1504);
PAINT GREEN (-941 1504);
DISPLAY INVISIBLE (-941 1504);
FORCEPROP 2 LAST PACK_TYPE C0201
J 2
(-1125 1475);
DISPLAY 0.553191 (-1125 1475);
DISPLAY INVISIBLE (-1125 1475);
FORCEPROP 2 LAST TOLERANCE 20%
J 2
(-1025 1475);
DISPLAY 0.553191 (-1025 1475);
DISPLAY INVISIBLE (-1025 1475);
FORCEPROP 1 LAST PART_NUMBER SP_CH4221MEE01
J 2
(-1066 1513);
DISPLAY 0.574468 (-1066 1513);
PAINT GREEN (-1066 1513);
DISPLAY INVISIBLE (-1066 1513);
FORCEPROP 1 LAST LOCATION C728
J 0
(-700 1500);
DISPLAY 1.021277 (-700 1500);
DISPLAY INVISIBLE (-700 1500);
FORCEPROP 1 LAST PATH I250
J 2
(-950 1425);
DISPLAY 0.723404 (-950 1425);
DISPLAY INVISIBLE (-950 1425);
FORCEADD Q_CAP_DIFFBUS..2
R 2
(-950 1575);
FORCEPROP 1 LAST LOCATION C727
J 2
(-716 1592);
DISPLAY 0.723404 (-716 1592);
PAINT GREEN (-716 1592);
FORCEPROP 2 LAST $SEC 1
J 2
(-775 1650);
DISPLAY 0.680851 (-775 1650);
PAINT MONO (-775 1650);
DISPLAY INVISIBLE (-775 1650);
FORCEPROP 2 LAST CDS_SEC 1
J 2
(-775 1650);
DISPLAY 0.680851 (-775 1650);
DISPLAY INVISIBLE (-775 1650);
FORCEPROP 2 LASTPIN (-875 1575) $PN 1
J 0
(-865 1585);
DISPLAY 0.808511 (-865 1585);
FORCEPROP 2 LASTPIN (-1025 1575) $PN 2
J 2
(-1035 1585);
DISPLAY 0.808511 (-1035 1585);
FORCEPROP 2 LAST VALUE DIFF BUS_0.22UF
J 2
(-1100 1575);
DISPLAY 0.553191 (-1100 1575);
FORCEPROP 1 LAST PIN_NAMES_ROTATE TRUE
J 2
(-950 1575);
DISPLAY 0.489362 (-950 1575);
PAINT GREEN (-950 1575);
DISPLAY INVISIBLE (-950 1575);
FORCEPROP 2 LAST CDS_LIB pure_quanta
J 2
(-950 1575);
DISPLAY INVISIBLE (-950 1575);
FORCEPROP 1 LAST CDS_LMAN_SYM_OUTLINE -25,50,25,-50
J 2
(-950 1575);
DISPLAY 0.468085 (-950 1575);
PAINT GREEN (-950 1575);
DISPLAY INVISIBLE (-950 1575);
FORCEPROP 2 LAST VOLTAGE 6.3V
J 2
(-1300 1625);
DISPLAY 0.553191 (-1300 1625);
DISPLAY INVISIBLE (-1300 1625);
FORCEPROP 1 LAST MATERIAL X6S
J 2
(-941 1654);
DISPLAY 0.574468 (-941 1654);
PAINT GREEN (-941 1654);
DISPLAY INVISIBLE (-941 1654);
FORCEPROP 2 LAST PACK_TYPE C0201
J 2
(-1125 1625);
DISPLAY 0.553191 (-1125 1625);
DISPLAY INVISIBLE (-1125 1625);
FORCEPROP 2 LAST TOLERANCE 20%
J 2
(-1025 1625);
DISPLAY 0.553191 (-1025 1625);
DISPLAY INVISIBLE (-1025 1625);
FORCEPROP 1 LAST PART_NUMBER SP_CH4221MEE01
J 2
(-1066 1663);
DISPLAY 0.574468 (-1066 1663);
PAINT GREEN (-1066 1663);
DISPLAY INVISIBLE (-1066 1663);
FORCEPROP 1 LAST LOCATION C727
J 0
(-700 1650);
DISPLAY 1.021277 (-700 1650);
DISPLAY INVISIBLE (-700 1650);
FORCEPROP 1 LAST PATH I251
J 2
(-950 1575);
DISPLAY 0.723404 (-950 1575);
DISPLAY INVISIBLE (-950 1575);
FORCEADD TAP..1
(-400 1025);
FORCEPROP 3 LASTPIN (-450 1025) SIG_NAME P5E_CPU1_P1_TX_C_DN<4>
J 0
(-440 1035);
DISPLAY 0.659574 (-440 1035);
PAINT MONO (-440 1035);
DISPLAY INVISIBLE (-440 1035);
FORCEPROP 1 LASTPIN (-450 1025) BN 4
J 0
(-462 1033);
DISPLAY 0.680851 (-462 1033);
PAINT GREEN (-462 1033);
FORCEPROP 2 LAST CDS_LIB standard
J 0
(-400 1025);
DISPLAY INVISIBLE (-400 1025);
FORCEPROP 1 LAST BODY_TYPE PLUMBING
J 0
(-400 1075);
DISPLAY 0.872340 (-400 1075);
PAINT GREEN (-400 1075);
DISPLAY INVISIBLE (-400 1075);
FORCEPROP 1 LAST HDL_TAP TRUE
J 0
(-75 900);
DISPLAY 0.872340 (-75 900);
DISPLAY INVISIBLE (-75 900);
FORCEPROP 1 LAST PATH I252
J 0
(-402 1025);
DISPLAY 0.872340 (-402 1025);
PAINT GREEN (-402 1025);
DISPLAY INVISIBLE (-402 1025);
FORCEADD TAP..1
(-400 1425);
FORCEPROP 3 LASTPIN (-450 1425) SIG_NAME P5E_CPU1_P1_TX_C_DN<6>
J 0
(-440 1435);
DISPLAY 0.659574 (-440 1435);
PAINT MONO (-440 1435);
DISPLAY INVISIBLE (-440 1435);
FORCEPROP 1 LASTPIN (-450 1425) BN 6
J 0
(-462 1433);
DISPLAY 0.680851 (-462 1433);
PAINT GREEN (-462 1433);
FORCEPROP 2 LAST CDS_LIB standard
J 0
(-400 1425);
DISPLAY INVISIBLE (-400 1425);
FORCEPROP 1 LAST BODY_TYPE PLUMBING
J 0
(-400 1475);
DISPLAY 0.872340 (-400 1475);
PAINT GREEN (-400 1475);
DISPLAY INVISIBLE (-400 1475);
FORCEPROP 1 LAST HDL_TAP TRUE
J 0
(-75 1300);
DISPLAY 0.872340 (-75 1300);
DISPLAY INVISIBLE (-75 1300);
FORCEPROP 1 LAST PATH I253
J 0
(-402 1425);
DISPLAY 0.872340 (-402 1425);
PAINT GREEN (-402 1425);
DISPLAY INVISIBLE (-402 1425);
FORCEADD TAP..1
(-200 1175);
FORCEPROP 3 LASTPIN (-250 1175) SIG_NAME P5E_CPU1_P1_TX_C_DP<5>
J 0
(-240 1185);
DISPLAY 0.659574 (-240 1185);
PAINT MONO (-240 1185);
DISPLAY INVISIBLE (-240 1185);
FORCEPROP 1 LASTPIN (-250 1175) BN 5
J 0
(-262 1183);
DISPLAY 0.680851 (-262 1183);
PAINT GREEN (-262 1183);
FORCEPROP 2 LAST CDS_LIB standard
J 0
(-200 1175);
DISPLAY INVISIBLE (-200 1175);
FORCEPROP 1 LAST BODY_TYPE PLUMBING
J 0
(-200 1225);
DISPLAY 0.872340 (-200 1225);
PAINT GREEN (-200 1225);
DISPLAY INVISIBLE (-200 1225);
FORCEPROP 1 LAST HDL_TAP TRUE
J 0
(125 1050);
DISPLAY 0.872340 (125 1050);
DISPLAY INVISIBLE (125 1050);
FORCEPROP 1 LAST PATH I254
J 0
(-202 1175);
DISPLAY 0.872340 (-202 1175);
PAINT GREEN (-202 1175);
DISPLAY INVISIBLE (-202 1175);
FORCEADD TAP..1
(-200 1375);
FORCEPROP 3 LASTPIN (-250 1375) SIG_NAME P5E_CPU1_P1_TX_C_DP<6>
J 0
(-240 1385);
DISPLAY 0.659574 (-240 1385);
PAINT MONO (-240 1385);
DISPLAY INVISIBLE (-240 1385);
FORCEPROP 1 LASTPIN (-250 1375) BN 6
J 0
(-262 1383);
DISPLAY 0.680851 (-262 1383);
PAINT GREEN (-262 1383);
FORCEPROP 2 LAST CDS_LIB standard
J 0
(-200 1375);
DISPLAY INVISIBLE (-200 1375);
FORCEPROP 1 LAST BODY_TYPE PLUMBING
J 0
(-200 1425);
DISPLAY 0.872340 (-200 1425);
PAINT GREEN (-200 1425);
DISPLAY INVISIBLE (-200 1425);
FORCEPROP 1 LAST HDL_TAP TRUE
J 0
(125 1250);
DISPLAY 0.872340 (125 1250);
DISPLAY INVISIBLE (125 1250);
FORCEPROP 1 LAST PATH I255
J 0
(-202 1375);
DISPLAY 0.872340 (-202 1375);
PAINT GREEN (-202 1375);
DISPLAY INVISIBLE (-202 1375);
FORCEADD TAP..1
(-400 1625);
FORCEPROP 3 LASTPIN (-450 1625) SIG_NAME P5E_CPU1_P1_TX_C_DN<7>
J 0
(-440 1635);
DISPLAY 0.659574 (-440 1635);
PAINT MONO (-440 1635);
DISPLAY INVISIBLE (-440 1635);
FORCEPROP 1 LASTPIN (-450 1625) BN 7
J 0
(-462 1633);
DISPLAY 0.680851 (-462 1633);
PAINT GREEN (-462 1633);
FORCEPROP 2 LAST CDS_LIB standard
J 0
(-400 1625);
DISPLAY INVISIBLE (-400 1625);
FORCEPROP 1 LAST BODY_TYPE PLUMBING
J 0
(-400 1675);
DISPLAY 0.872340 (-400 1675);
PAINT GREEN (-400 1675);
DISPLAY INVISIBLE (-400 1675);
FORCEPROP 1 LAST HDL_TAP TRUE
J 0
(-75 1500);
DISPLAY 0.872340 (-75 1500);
DISPLAY INVISIBLE (-75 1500);
FORCEPROP 1 LAST PATH I256
J 0
(-402 1625);
DISPLAY 0.872340 (-402 1625);
PAINT GREEN (-402 1625);
DISPLAY INVISIBLE (-402 1625);
FORCEADD TAP..1
(-200 1575);
FORCEPROP 3 LASTPIN (-250 1575) SIG_NAME P5E_CPU1_P1_TX_C_DP<7>
J 0
(-240 1585);
DISPLAY 0.659574 (-240 1585);
PAINT MONO (-240 1585);
DISPLAY INVISIBLE (-240 1585);
FORCEPROP 1 LASTPIN (-250 1575) BN 7
J 0
(-262 1583);
DISPLAY 0.680851 (-262 1583);
PAINT GREEN (-262 1583);
FORCEPROP 2 LAST CDS_LIB standard
J 0
(-200 1575);
DISPLAY INVISIBLE (-200 1575);
FORCEPROP 1 LAST BODY_TYPE PLUMBING
J 0
(-200 1625);
DISPLAY 0.872340 (-200 1625);
PAINT GREEN (-200 1625);
DISPLAY INVISIBLE (-200 1625);
FORCEPROP 1 LAST HDL_TAP TRUE
J 0
(125 1450);
DISPLAY 0.872340 (125 1450);
DISPLAY INVISIBLE (125 1450);
FORCEPROP 1 LAST PATH I257
J 0
(-202 1575);
DISPLAY 0.872340 (-202 1575);
PAINT GREEN (-202 1575);
DISPLAY INVISIBLE (-202 1575);
FORCEADD TAP..1
R 2
(-1925 2150);
FORCEPROP 3 LASTPIN (-1875 2150) SIG_NAME P5E_CPU1_P1_TX_DP<8>
J 0
(-1865 2160);
DISPLAY 0.659574 (-1865 2160);
PAINT MONO (-1865 2160);
DISPLAY INVISIBLE (-1865 2160);
FORCEPROP 1 LASTPIN (-1875 2150) BN 8
J 2
(-1863 2158);
DISPLAY 0.680851 (-1863 2158);
PAINT GREEN (-1863 2158);
FORCEPROP 2 LAST CDS_LIB standard
J 0
(-1925 2150);
DISPLAY INVISIBLE (-1925 2150);
FORCEPROP 1 LAST BODY_TYPE PLUMBING
J 2
(-1925 2200);
DISPLAY 0.872340 (-1925 2200);
PAINT GREEN (-1925 2200);
DISPLAY INVISIBLE (-1925 2200);
FORCEPROP 1 LAST HDL_TAP TRUE
J 2
(-2250 2025);
DISPLAY 0.872340 (-2250 2025);
DISPLAY INVISIBLE (-2250 2025);
FORCEPROP 1 LAST PATH I258
J 2
(-1923 2150);
DISPLAY 0.872340 (-1923 2150);
PAINT GREEN (-1923 2150);
DISPLAY INVISIBLE (-1923 2150);
FORCEADD TAP..1
R 2
(-1925 2350);
FORCEPROP 3 LASTPIN (-1875 2350) SIG_NAME P5E_CPU1_P1_TX_DP<9>
J 0
(-1865 2360);
DISPLAY 0.659574 (-1865 2360);
PAINT MONO (-1865 2360);
DISPLAY INVISIBLE (-1865 2360);
FORCEPROP 1 LASTPIN (-1875 2350) BN 9
J 2
(-1863 2358);
DISPLAY 0.680851 (-1863 2358);
PAINT GREEN (-1863 2358);
FORCEPROP 2 LAST CDS_LIB standard
J 0
(-1925 2350);
DISPLAY INVISIBLE (-1925 2350);
FORCEPROP 1 LAST BODY_TYPE PLUMBING
J 2
(-1925 2400);
DISPLAY 0.872340 (-1925 2400);
PAINT GREEN (-1925 2400);
DISPLAY INVISIBLE (-1925 2400);
FORCEPROP 1 LAST HDL_TAP TRUE
J 2
(-2250 2225);
DISPLAY 0.872340 (-2250 2225);
DISPLAY INVISIBLE (-2250 2225);
FORCEPROP 1 LAST PATH I259
J 2
(-1923 2350);
DISPLAY 0.872340 (-1923 2350);
PAINT GREEN (-1923 2350);
DISPLAY INVISIBLE (-1923 2350);
FORCEADD TAP..1
R 2
(-1675 2200);
FORCEPROP 3 LASTPIN (-1625 2200) SIG_NAME P5E_CPU1_P1_TX_DN<8>
J 0
(-1615 2210);
DISPLAY 0.659574 (-1615 2210);
PAINT MONO (-1615 2210);
DISPLAY INVISIBLE (-1615 2210);
FORCEPROP 1 LASTPIN (-1625 2200) BN 8
J 2
(-1613 2208);
DISPLAY 0.680851 (-1613 2208);
PAINT GREEN (-1613 2208);
FORCEPROP 2 LAST CDS_LIB standard
J 0
(-1675 2200);
DISPLAY INVISIBLE (-1675 2200);
FORCEPROP 1 LAST BODY_TYPE PLUMBING
J 2
(-1675 2250);
DISPLAY 0.872340 (-1675 2250);
PAINT GREEN (-1675 2250);
DISPLAY INVISIBLE (-1675 2250);
FORCEPROP 1 LAST HDL_TAP TRUE
J 2
(-2000 2075);
DISPLAY 0.872340 (-2000 2075);
DISPLAY INVISIBLE (-2000 2075);
FORCEPROP 1 LAST PATH I260
J 2
(-1673 2200);
DISPLAY 0.872340 (-1673 2200);
PAINT GREEN (-1673 2200);
DISPLAY INVISIBLE (-1673 2200);
FORCEADD TAP..1
R 2
(-1675 2400);
FORCEPROP 3 LASTPIN (-1625 2400) SIG_NAME P5E_CPU1_P1_TX_DN<9>
J 0
(-1615 2410);
DISPLAY 0.659574 (-1615 2410);
PAINT MONO (-1615 2410);
DISPLAY INVISIBLE (-1615 2410);
FORCEPROP 1 LASTPIN (-1625 2400) BN 9
J 2
(-1613 2408);
DISPLAY 0.680851 (-1613 2408);
PAINT GREEN (-1613 2408);
FORCEPROP 2 LAST CDS_LIB standard
J 0
(-1675 2400);
DISPLAY INVISIBLE (-1675 2400);
FORCEPROP 1 LAST BODY_TYPE PLUMBING
J 2
(-1675 2450);
DISPLAY 0.872340 (-1675 2450);
PAINT GREEN (-1675 2450);
DISPLAY INVISIBLE (-1675 2450);
FORCEPROP 1 LAST HDL_TAP TRUE
J 2
(-2000 2275);
DISPLAY 0.872340 (-2000 2275);
DISPLAY INVISIBLE (-2000 2275);
FORCEPROP 1 LAST PATH I261
J 2
(-1673 2400);
DISPLAY 0.872340 (-1673 2400);
PAINT GREEN (-1673 2400);
DISPLAY INVISIBLE (-1673 2400);
FORCEADD TAP..1
R 2
(-1925 2750);
FORCEPROP 3 LASTPIN (-1875 2750) SIG_NAME P5E_CPU1_P1_TX_DP<11>
J 0
(-1865 2760);
DISPLAY 0.659574 (-1865 2760);
PAINT MONO (-1865 2760);
DISPLAY INVISIBLE (-1865 2760);
FORCEPROP 1 LASTPIN (-1875 2750) BN 11
J 2
(-1863 2758);
DISPLAY 0.680851 (-1863 2758);
PAINT GREEN (-1863 2758);
FORCEPROP 2 LAST CDS_LIB standard
J 0
(-1925 2750);
DISPLAY INVISIBLE (-1925 2750);
FORCEPROP 1 LAST BODY_TYPE PLUMBING
J 2
(-1925 2800);
DISPLAY 0.872340 (-1925 2800);
PAINT GREEN (-1925 2800);
DISPLAY INVISIBLE (-1925 2800);
FORCEPROP 1 LAST HDL_TAP TRUE
J 2
(-2250 2625);
DISPLAY 0.872340 (-2250 2625);
DISPLAY INVISIBLE (-2250 2625);
FORCEPROP 1 LAST PATH I262
J 2
(-1923 2750);
DISPLAY 0.872340 (-1923 2750);
PAINT GREEN (-1923 2750);
DISPLAY INVISIBLE (-1923 2750);
FORCEADD TAP..1
R 2
(-1925 2550);
FORCEPROP 3 LASTPIN (-1875 2550) SIG_NAME P5E_CPU1_P1_TX_DP<10>
J 0
(-1865 2560);
DISPLAY 0.659574 (-1865 2560);
PAINT MONO (-1865 2560);
DISPLAY INVISIBLE (-1865 2560);
FORCEPROP 1 LASTPIN (-1875 2550) BN 10
J 2
(-1863 2558);
DISPLAY 0.680851 (-1863 2558);
PAINT GREEN (-1863 2558);
FORCEPROP 2 LAST CDS_LIB standard
J 0
(-1925 2550);
DISPLAY INVISIBLE (-1925 2550);
FORCEPROP 1 LAST BODY_TYPE PLUMBING
J 2
(-1925 2600);
DISPLAY 0.872340 (-1925 2600);
PAINT GREEN (-1925 2600);
DISPLAY INVISIBLE (-1925 2600);
FORCEPROP 1 LAST HDL_TAP TRUE
J 2
(-2250 2425);
DISPLAY 0.872340 (-2250 2425);
DISPLAY INVISIBLE (-2250 2425);
FORCEPROP 1 LAST PATH I263
J 2
(-1923 2550);
DISPLAY 0.872340 (-1923 2550);
PAINT GREEN (-1923 2550);
DISPLAY INVISIBLE (-1923 2550);
FORCEADD TAP..1
R 2
(-1925 2950);
FORCEPROP 3 LASTPIN (-1875 2950) SIG_NAME P5E_CPU1_P1_TX_DP<12>
J 0
(-1865 2960);
DISPLAY 0.659574 (-1865 2960);
PAINT MONO (-1865 2960);
DISPLAY INVISIBLE (-1865 2960);
FORCEPROP 1 LASTPIN (-1875 2950) BN 12
J 2
(-1863 2958);
DISPLAY 0.680851 (-1863 2958);
PAINT GREEN (-1863 2958);
FORCEPROP 2 LAST CDS_LIB standard
J 0
(-1925 2950);
DISPLAY INVISIBLE (-1925 2950);
FORCEPROP 1 LAST BODY_TYPE PLUMBING
J 2
(-1925 3000);
DISPLAY 0.872340 (-1925 3000);
PAINT GREEN (-1925 3000);
DISPLAY INVISIBLE (-1925 3000);
FORCEPROP 1 LAST HDL_TAP TRUE
J 2
(-2250 2825);
DISPLAY 0.872340 (-2250 2825);
DISPLAY INVISIBLE (-2250 2825);
FORCEPROP 1 LAST PATH I264
J 2
(-1923 2950);
DISPLAY 0.872340 (-1923 2950);
PAINT GREEN (-1923 2950);
DISPLAY INVISIBLE (-1923 2950);
FORCEADD TAP..1
R 2
(-1675 2600);
FORCEPROP 3 LASTPIN (-1625 2600) SIG_NAME P5E_CPU1_P1_TX_DN<10>
J 0
(-1615 2610);
DISPLAY 0.659574 (-1615 2610);
PAINT MONO (-1615 2610);
DISPLAY INVISIBLE (-1615 2610);
FORCEPROP 1 LASTPIN (-1625 2600) BN 10
J 2
(-1613 2608);
DISPLAY 0.680851 (-1613 2608);
PAINT GREEN (-1613 2608);
FORCEPROP 2 LAST CDS_LIB standard
J 0
(-1675 2600);
DISPLAY INVISIBLE (-1675 2600);
FORCEPROP 1 LAST BODY_TYPE PLUMBING
J 2
(-1675 2650);
DISPLAY 0.872340 (-1675 2650);
PAINT GREEN (-1675 2650);
DISPLAY INVISIBLE (-1675 2650);
FORCEPROP 1 LAST HDL_TAP TRUE
J 2
(-2000 2475);
DISPLAY 0.872340 (-2000 2475);
DISPLAY INVISIBLE (-2000 2475);
FORCEPROP 1 LAST PATH I265
J 2
(-1673 2600);
DISPLAY 0.872340 (-1673 2600);
PAINT GREEN (-1673 2600);
DISPLAY INVISIBLE (-1673 2600);
FORCEADD TAP..1
R 2
(-1675 2800);
FORCEPROP 3 LASTPIN (-1625 2800) SIG_NAME P5E_CPU1_P1_TX_DN<11>
J 0
(-1615 2810);
DISPLAY 0.659574 (-1615 2810);
PAINT MONO (-1615 2810);
DISPLAY INVISIBLE (-1615 2810);
FORCEPROP 1 LASTPIN (-1625 2800) BN 11
J 2
(-1613 2808);
DISPLAY 0.680851 (-1613 2808);
PAINT GREEN (-1613 2808);
FORCEPROP 2 LAST CDS_LIB standard
J 0
(-1675 2800);
DISPLAY INVISIBLE (-1675 2800);
FORCEPROP 1 LAST BODY_TYPE PLUMBING
J 2
(-1675 2850);
DISPLAY 0.872340 (-1675 2850);
PAINT GREEN (-1675 2850);
DISPLAY INVISIBLE (-1675 2850);
FORCEPROP 1 LAST HDL_TAP TRUE
J 2
(-2000 2675);
DISPLAY 0.872340 (-2000 2675);
DISPLAY INVISIBLE (-2000 2675);
FORCEPROP 1 LAST PATH I266
J 2
(-1673 2800);
DISPLAY 0.872340 (-1673 2800);
PAINT GREEN (-1673 2800);
DISPLAY INVISIBLE (-1673 2800);
FORCEADD TAP..1
R 2
(-1675 3000);
FORCEPROP 3 LASTPIN (-1625 3000) SIG_NAME P5E_CPU1_P1_TX_DN<12>
J 0
(-1615 3010);
DISPLAY 0.659574 (-1615 3010);
PAINT MONO (-1615 3010);
DISPLAY INVISIBLE (-1615 3010);
FORCEPROP 1 LASTPIN (-1625 3000) BN 12
J 2
(-1613 3008);
DISPLAY 0.680851 (-1613 3008);
PAINT GREEN (-1613 3008);
FORCEPROP 2 LAST CDS_LIB standard
J 0
(-1675 3000);
DISPLAY INVISIBLE (-1675 3000);
FORCEPROP 1 LAST BODY_TYPE PLUMBING
J 2
(-1675 3050);
DISPLAY 0.872340 (-1675 3050);
PAINT GREEN (-1675 3050);
DISPLAY INVISIBLE (-1675 3050);
FORCEPROP 1 LAST HDL_TAP TRUE
J 2
(-2000 2875);
DISPLAY 0.872340 (-2000 2875);
DISPLAY INVISIBLE (-2000 2875);
FORCEPROP 1 LAST PATH I267
J 2
(-1673 3000);
DISPLAY 0.872340 (-1673 3000);
PAINT GREEN (-1673 3000);
DISPLAY INVISIBLE (-1673 3000);
FORCEADD TAP..1
R 2
(-1925 3150);
FORCEPROP 3 LASTPIN (-1875 3150) SIG_NAME P5E_CPU1_P1_TX_DP<13>
J 0
(-1865 3160);
DISPLAY 0.659574 (-1865 3160);
PAINT MONO (-1865 3160);
DISPLAY INVISIBLE (-1865 3160);
FORCEPROP 1 LASTPIN (-1875 3150) BN 13
J 2
(-1863 3158);
DISPLAY 0.680851 (-1863 3158);
PAINT GREEN (-1863 3158);
FORCEPROP 2 LAST CDS_LIB standard
J 0
(-1925 3150);
DISPLAY INVISIBLE (-1925 3150);
FORCEPROP 1 LAST BODY_TYPE PLUMBING
J 2
(-1925 3200);
DISPLAY 0.872340 (-1925 3200);
PAINT GREEN (-1925 3200);
DISPLAY INVISIBLE (-1925 3200);
FORCEPROP 1 LAST HDL_TAP TRUE
J 2
(-2250 3025);
DISPLAY 0.872340 (-2250 3025);
DISPLAY INVISIBLE (-2250 3025);
FORCEPROP 1 LAST PATH I268
J 2
(-1923 3150);
DISPLAY 0.872340 (-1923 3150);
PAINT GREEN (-1923 3150);
DISPLAY INVISIBLE (-1923 3150);
FORCEADD TAP..1
R 2
(-1925 3350);
FORCEPROP 3 LASTPIN (-1875 3350) SIG_NAME P5E_CPU1_P1_TX_DP<14>
J 0
(-1865 3360);
DISPLAY 0.659574 (-1865 3360);
PAINT MONO (-1865 3360);
DISPLAY INVISIBLE (-1865 3360);
FORCEPROP 1 LASTPIN (-1875 3350) BN 14
J 2
(-1863 3358);
DISPLAY 0.680851 (-1863 3358);
PAINT GREEN (-1863 3358);
FORCEPROP 2 LAST CDS_LIB standard
J 0
(-1925 3350);
DISPLAY INVISIBLE (-1925 3350);
FORCEPROP 1 LAST BODY_TYPE PLUMBING
J 2
(-1925 3400);
DISPLAY 0.872340 (-1925 3400);
PAINT GREEN (-1925 3400);
DISPLAY INVISIBLE (-1925 3400);
FORCEPROP 1 LAST HDL_TAP TRUE
J 2
(-2250 3225);
DISPLAY 0.872340 (-2250 3225);
DISPLAY INVISIBLE (-2250 3225);
FORCEPROP 1 LAST PATH I269
J 2
(-1923 3350);
DISPLAY 0.872340 (-1923 3350);
PAINT GREEN (-1923 3350);
DISPLAY INVISIBLE (-1923 3350);
FORCEADD TAP..1
R 2
(-1925 3550);
FORCEPROP 3 LASTPIN (-1875 3550) SIG_NAME P5E_CPU1_P1_TX_DP<15>
J 0
(-1865 3560);
DISPLAY 0.659574 (-1865 3560);
PAINT MONO (-1865 3560);
DISPLAY INVISIBLE (-1865 3560);
FORCEPROP 1 LASTPIN (-1875 3550) BN 15
J 2
(-1863 3558);
DISPLAY 0.680851 (-1863 3558);
PAINT GREEN (-1863 3558);
FORCEPROP 2 LAST CDS_LIB standard
J 0
(-1925 3550);
DISPLAY INVISIBLE (-1925 3550);
FORCEPROP 1 LAST BODY_TYPE PLUMBING
J 2
(-1925 3600);
DISPLAY 0.872340 (-1925 3600);
PAINT GREEN (-1925 3600);
DISPLAY INVISIBLE (-1925 3600);
FORCEPROP 1 LAST HDL_TAP TRUE
J 2
(-2250 3425);
DISPLAY 0.872340 (-2250 3425);
DISPLAY INVISIBLE (-2250 3425);
FORCEPROP 1 LAST PATH I270
J 2
(-1923 3550);
DISPLAY 0.872340 (-1923 3550);
PAINT GREEN (-1923 3550);
DISPLAY INVISIBLE (-1923 3550);
FORCEADD TAP..1
R 2
(-1675 3200);
FORCEPROP 3 LASTPIN (-1625 3200) SIG_NAME P5E_CPU1_P1_TX_DN<13>
J 0
(-1615 3210);
DISPLAY 0.659574 (-1615 3210);
PAINT MONO (-1615 3210);
DISPLAY INVISIBLE (-1615 3210);
FORCEPROP 1 LASTPIN (-1625 3200) BN 13
J 2
(-1613 3208);
DISPLAY 0.680851 (-1613 3208);
PAINT GREEN (-1613 3208);
FORCEPROP 2 LAST CDS_LIB standard
J 0
(-1675 3200);
DISPLAY INVISIBLE (-1675 3200);
FORCEPROP 1 LAST BODY_TYPE PLUMBING
J 2
(-1675 3250);
DISPLAY 0.872340 (-1675 3250);
PAINT GREEN (-1675 3250);
DISPLAY INVISIBLE (-1675 3250);
FORCEPROP 1 LAST HDL_TAP TRUE
J 2
(-2000 3075);
DISPLAY 0.872340 (-2000 3075);
DISPLAY INVISIBLE (-2000 3075);
FORCEPROP 1 LAST PATH I271
J 2
(-1673 3200);
DISPLAY 0.872340 (-1673 3200);
PAINT GREEN (-1673 3200);
DISPLAY INVISIBLE (-1673 3200);
FORCEADD TAP..1
R 2
(-1675 3400);
FORCEPROP 3 LASTPIN (-1625 3400) SIG_NAME P5E_CPU1_P1_TX_DN<14>
J 0
(-1615 3410);
DISPLAY 0.659574 (-1615 3410);
PAINT MONO (-1615 3410);
DISPLAY INVISIBLE (-1615 3410);
FORCEPROP 1 LASTPIN (-1625 3400) BN 14
J 2
(-1613 3408);
DISPLAY 0.680851 (-1613 3408);
PAINT GREEN (-1613 3408);
FORCEPROP 2 LAST CDS_LIB standard
J 0
(-1675 3400);
DISPLAY INVISIBLE (-1675 3400);
FORCEPROP 1 LAST BODY_TYPE PLUMBING
J 2
(-1675 3450);
DISPLAY 0.872340 (-1675 3450);
PAINT GREEN (-1675 3450);
DISPLAY INVISIBLE (-1675 3450);
FORCEPROP 1 LAST HDL_TAP TRUE
J 2
(-2000 3275);
DISPLAY 0.872340 (-2000 3275);
DISPLAY INVISIBLE (-2000 3275);
FORCEPROP 1 LAST PATH I272
J 2
(-1673 3400);
DISPLAY 0.872340 (-1673 3400);
PAINT GREEN (-1673 3400);
DISPLAY INVISIBLE (-1673 3400);
FORCEADD TAP..1
R 2
(-1675 3600);
FORCEPROP 3 LASTPIN (-1625 3600) SIG_NAME P5E_CPU1_P1_TX_DN<15>
J 0
(-1615 3610);
DISPLAY 0.659574 (-1615 3610);
PAINT MONO (-1615 3610);
DISPLAY INVISIBLE (-1615 3610);
FORCEPROP 1 LASTPIN (-1625 3600) BN 15
J 2
(-1613 3608);
DISPLAY 0.680851 (-1613 3608);
PAINT GREEN (-1613 3608);
FORCEPROP 2 LAST CDS_LIB standard
J 0
(-1675 3600);
DISPLAY INVISIBLE (-1675 3600);
FORCEPROP 1 LAST BODY_TYPE PLUMBING
J 2
(-1675 3650);
DISPLAY 0.872340 (-1675 3650);
PAINT GREEN (-1675 3650);
DISPLAY INVISIBLE (-1675 3650);
FORCEPROP 1 LAST HDL_TAP TRUE
J 2
(-2000 3475);
DISPLAY 0.872340 (-2000 3475);
DISPLAY INVISIBLE (-2000 3475);
FORCEPROP 1 LAST PATH I273
J 2
(-1673 3600);
DISPLAY 0.872340 (-1673 3600);
PAINT GREEN (-1673 3600);
DISPLAY INVISIBLE (-1673 3600);
FORCEADD Q_CAP_DIFFBUS..2
R 2
(-950 2150);
FORCEPROP 1 LAST LOCATION C725
J 2
(-716 2167);
DISPLAY 0.723404 (-716 2167);
PAINT GREEN (-716 2167);
FORCEPROP 2 LAST $SEC 1
J 2
(-775 2225);
DISPLAY 0.680851 (-775 2225);
PAINT MONO (-775 2225);
DISPLAY INVISIBLE (-775 2225);
FORCEPROP 2 LAST CDS_SEC 1
J 2
(-775 2225);
DISPLAY 0.680851 (-775 2225);
DISPLAY INVISIBLE (-775 2225);
FORCEPROP 2 LASTPIN (-875 2150) $PN 1
J 0
(-865 2160);
DISPLAY 0.808511 (-865 2160);
FORCEPROP 2 LASTPIN (-1025 2150) $PN 2
J 2
(-1035 2160);
DISPLAY 0.808511 (-1035 2160);
FORCEPROP 2 LAST VALUE DIFF BUS_0.22UF
J 2
(-1100 2150);
DISPLAY 0.553191 (-1100 2150);
FORCEPROP 1 LAST CDS_LMAN_SYM_OUTLINE -25,50,25,-50
J 2
(-950 2150);
DISPLAY 0.468085 (-950 2150);
PAINT GREEN (-950 2150);
DISPLAY INVISIBLE (-950 2150);
FORCEPROP 2 LAST CDS_LIB pure_quanta
J 2
(-950 2150);
DISPLAY INVISIBLE (-950 2150);
FORCEPROP 1 LAST PIN_NAMES_ROTATE TRUE
J 2
(-950 2150);
DISPLAY 0.489362 (-950 2150);
PAINT GREEN (-950 2150);
DISPLAY INVISIBLE (-950 2150);
FORCEPROP 2 LAST VOLTAGE 6.3V
J 2
(-1300 2200);
DISPLAY 0.553191 (-1300 2200);
DISPLAY INVISIBLE (-1300 2200);
FORCEPROP 1 LAST MATERIAL X6S
J 2
(-941 2229);
DISPLAY 0.574468 (-941 2229);
PAINT GREEN (-941 2229);
DISPLAY INVISIBLE (-941 2229);
FORCEPROP 2 LAST PACK_TYPE C0201
J 2
(-1125 2200);
DISPLAY 0.553191 (-1125 2200);
DISPLAY INVISIBLE (-1125 2200);
FORCEPROP 2 LAST TOLERANCE 20%
J 2
(-1025 2200);
DISPLAY 0.553191 (-1025 2200);
DISPLAY INVISIBLE (-1025 2200);
FORCEPROP 1 LAST PART_NUMBER SP_CH4221MEE01
J 2
(-1066 2238);
DISPLAY 0.574468 (-1066 2238);
PAINT GREEN (-1066 2238);
DISPLAY INVISIBLE (-1066 2238);
FORCEPROP 1 LAST LOCATION C725
J 0
(-700 2225);
DISPLAY 1.021277 (-700 2225);
DISPLAY INVISIBLE (-700 2225);
FORCEPROP 1 LAST PATH I274
J 2
(-950 2150);
DISPLAY 0.723404 (-950 2150);
DISPLAY INVISIBLE (-950 2150);
FORCEADD Q_CAP_DIFFBUS..2
R 2
(-950 2200);
FORCEPROP 1 LAST LOCATION C724
J 2
(-716 2217);
DISPLAY 0.723404 (-716 2217);
PAINT GREEN (-716 2217);
FORCEPROP 2 LAST $SEC 1
J 2
(-775 2275);
DISPLAY 0.680851 (-775 2275);
PAINT MONO (-775 2275);
DISPLAY INVISIBLE (-775 2275);
FORCEPROP 2 LAST CDS_SEC 1
J 2
(-775 2275);
DISPLAY 0.680851 (-775 2275);
DISPLAY INVISIBLE (-775 2275);
FORCEPROP 2 LASTPIN (-875 2200) $PN 1
J 0
(-865 2210);
DISPLAY 0.808511 (-865 2210);
FORCEPROP 2 LASTPIN (-1025 2200) $PN 2
J 2
(-1035 2210);
DISPLAY 0.808511 (-1035 2210);
FORCEPROP 2 LAST VALUE DIFF BUS_0.22UF
J 2
(-1100 2200);
DISPLAY 0.553191 (-1100 2200);
FORCEPROP 1 LAST CDS_LMAN_SYM_OUTLINE -25,50,25,-50
J 2
(-950 2200);
DISPLAY 0.468085 (-950 2200);
PAINT GREEN (-950 2200);
DISPLAY INVISIBLE (-950 2200);
FORCEPROP 2 LAST CDS_LIB pure_quanta
J 2
(-950 2200);
DISPLAY INVISIBLE (-950 2200);
FORCEPROP 1 LAST PIN_NAMES_ROTATE TRUE
J 2
(-950 2200);
DISPLAY 0.489362 (-950 2200);
PAINT GREEN (-950 2200);
DISPLAY INVISIBLE (-950 2200);
FORCEPROP 2 LAST VOLTAGE 6.3V
J 2
(-1300 2250);
DISPLAY 0.553191 (-1300 2250);
DISPLAY INVISIBLE (-1300 2250);
FORCEPROP 1 LAST MATERIAL X6S
J 2
(-941 2279);
DISPLAY 0.574468 (-941 2279);
PAINT GREEN (-941 2279);
DISPLAY INVISIBLE (-941 2279);
FORCEPROP 2 LAST PACK_TYPE C0201
J 2
(-1125 2250);
DISPLAY 0.553191 (-1125 2250);
DISPLAY INVISIBLE (-1125 2250);
FORCEPROP 2 LAST TOLERANCE 20%
J 2
(-1025 2250);
DISPLAY 0.553191 (-1025 2250);
DISPLAY INVISIBLE (-1025 2250);
FORCEPROP 1 LAST PART_NUMBER SP_CH4221MEE01
J 2
(-1066 2288);
DISPLAY 0.574468 (-1066 2288);
PAINT GREEN (-1066 2288);
DISPLAY INVISIBLE (-1066 2288);
FORCEPROP 1 LAST LOCATION C724
J 0
(-700 2275);
DISPLAY 1.021277 (-700 2275);
DISPLAY INVISIBLE (-700 2275);
FORCEPROP 1 LAST PATH I275
J 2
(-950 2200);
DISPLAY 0.723404 (-950 2200);
DISPLAY INVISIBLE (-950 2200);
FORCEADD Q_CAP_DIFFBUS..2
R 2
(-950 2400);
FORCEPROP 1 LAST LOCATION C722
J 2
(-716 2417);
DISPLAY 0.723404 (-716 2417);
PAINT GREEN (-716 2417);
FORCEPROP 2 LAST $SEC 1
J 2
(-775 2475);
DISPLAY 0.680851 (-775 2475);
PAINT MONO (-775 2475);
DISPLAY INVISIBLE (-775 2475);
FORCEPROP 2 LAST CDS_SEC 1
J 2
(-775 2475);
DISPLAY 0.680851 (-775 2475);
DISPLAY INVISIBLE (-775 2475);
FORCEPROP 2 LASTPIN (-875 2400) $PN 1
J 0
(-865 2410);
DISPLAY 0.808511 (-865 2410);
FORCEPROP 2 LASTPIN (-1025 2400) $PN 2
J 2
(-1035 2410);
DISPLAY 0.808511 (-1035 2410);
FORCEPROP 2 LAST VALUE DIFF BUS_0.22UF
J 2
(-1100 2400);
DISPLAY 0.553191 (-1100 2400);
FORCEPROP 2 LAST CDS_LIB pure_quanta
J 2
(-950 2400);
DISPLAY INVISIBLE (-950 2400);
FORCEPROP 1 LAST CDS_LMAN_SYM_OUTLINE -25,50,25,-50
J 2
(-950 2400);
DISPLAY 0.468085 (-950 2400);
PAINT GREEN (-950 2400);
DISPLAY INVISIBLE (-950 2400);
FORCEPROP 1 LAST PIN_NAMES_ROTATE TRUE
J 2
(-950 2400);
DISPLAY 0.489362 (-950 2400);
PAINT GREEN (-950 2400);
DISPLAY INVISIBLE (-950 2400);
FORCEPROP 2 LAST VOLTAGE 6.3V
J 2
(-1300 2450);
DISPLAY 0.553191 (-1300 2450);
DISPLAY INVISIBLE (-1300 2450);
FORCEPROP 1 LAST MATERIAL X6S
J 2
(-941 2479);
DISPLAY 0.574468 (-941 2479);
PAINT GREEN (-941 2479);
DISPLAY INVISIBLE (-941 2479);
FORCEPROP 2 LAST PACK_TYPE C0201
J 2
(-1125 2450);
DISPLAY 0.553191 (-1125 2450);
DISPLAY INVISIBLE (-1125 2450);
FORCEPROP 2 LAST TOLERANCE 20%
J 2
(-1025 2450);
DISPLAY 0.553191 (-1025 2450);
DISPLAY INVISIBLE (-1025 2450);
FORCEPROP 1 LAST PART_NUMBER SP_CH4221MEE01
J 2
(-1066 2488);
DISPLAY 0.574468 (-1066 2488);
PAINT GREEN (-1066 2488);
DISPLAY INVISIBLE (-1066 2488);
FORCEPROP 1 LAST LOCATION C722
J 0
(-700 2475);
DISPLAY 1.021277 (-700 2475);
DISPLAY INVISIBLE (-700 2475);
FORCEPROP 1 LAST PATH I276
J 2
(-950 2400);
DISPLAY 0.723404 (-950 2400);
DISPLAY INVISIBLE (-950 2400);
FORCEADD Q_CAP_DIFFBUS..2
R 2
(-950 2350);
FORCEPROP 1 LAST LOCATION C723
J 2
(-716 2367);
DISPLAY 0.723404 (-716 2367);
PAINT GREEN (-716 2367);
FORCEPROP 2 LAST $SEC 1
J 2
(-775 2425);
DISPLAY 0.680851 (-775 2425);
PAINT MONO (-775 2425);
DISPLAY INVISIBLE (-775 2425);
FORCEPROP 2 LAST CDS_SEC 1
J 2
(-775 2425);
DISPLAY 0.680851 (-775 2425);
DISPLAY INVISIBLE (-775 2425);
FORCEPROP 2 LASTPIN (-875 2350) $PN 1
J 0
(-865 2360);
DISPLAY 0.808511 (-865 2360);
FORCEPROP 2 LASTPIN (-1025 2350) $PN 2
J 2
(-1035 2360);
DISPLAY 0.808511 (-1035 2360);
FORCEPROP 2 LAST VALUE DIFF BUS_0.22UF
J 2
(-1100 2350);
DISPLAY 0.553191 (-1100 2350);
FORCEPROP 1 LAST CDS_LMAN_SYM_OUTLINE -25,50,25,-50
J 2
(-950 2350);
DISPLAY 0.468085 (-950 2350);
PAINT GREEN (-950 2350);
DISPLAY INVISIBLE (-950 2350);
FORCEPROP 2 LAST CDS_LIB pure_quanta
J 2
(-950 2350);
DISPLAY INVISIBLE (-950 2350);
FORCEPROP 1 LAST PIN_NAMES_ROTATE TRUE
J 2
(-950 2350);
DISPLAY 0.489362 (-950 2350);
PAINT GREEN (-950 2350);
DISPLAY INVISIBLE (-950 2350);
FORCEPROP 2 LAST VOLTAGE 6.3V
J 2
(-1300 2400);
DISPLAY 0.553191 (-1300 2400);
DISPLAY INVISIBLE (-1300 2400);
FORCEPROP 1 LAST MATERIAL X6S
J 2
(-941 2429);
DISPLAY 0.574468 (-941 2429);
PAINT GREEN (-941 2429);
DISPLAY INVISIBLE (-941 2429);
FORCEPROP 2 LAST PACK_TYPE C0201
J 2
(-1125 2400);
DISPLAY 0.553191 (-1125 2400);
DISPLAY INVISIBLE (-1125 2400);
FORCEPROP 2 LAST TOLERANCE 20%
J 2
(-1025 2400);
DISPLAY 0.553191 (-1025 2400);
DISPLAY INVISIBLE (-1025 2400);
FORCEPROP 1 LAST PART_NUMBER SP_CH4221MEE01
J 2
(-1066 2438);
DISPLAY 0.574468 (-1066 2438);
PAINT GREEN (-1066 2438);
DISPLAY INVISIBLE (-1066 2438);
FORCEPROP 1 LAST LOCATION C723
J 0
(-700 2425);
DISPLAY 1.021277 (-700 2425);
DISPLAY INVISIBLE (-700 2425);
FORCEPROP 1 LAST PATH I277
J 2
(-950 2350);
DISPLAY 0.723404 (-950 2350);
DISPLAY INVISIBLE (-950 2350);
FORCEADD Q_CAP_DIFFBUS..2
R 2
(-950 2550);
FORCEPROP 1 LAST LOCATION C721
J 2
(-716 2567);
DISPLAY 0.723404 (-716 2567);
PAINT GREEN (-716 2567);
FORCEPROP 2 LAST $SEC 1
J 2
(-775 2625);
DISPLAY 0.680851 (-775 2625);
PAINT MONO (-775 2625);
DISPLAY INVISIBLE (-775 2625);
FORCEPROP 2 LAST CDS_SEC 1
J 2
(-775 2625);
DISPLAY 0.680851 (-775 2625);
DISPLAY INVISIBLE (-775 2625);
FORCEPROP 2 LASTPIN (-875 2550) $PN 1
J 0
(-865 2560);
DISPLAY 0.808511 (-865 2560);
FORCEPROP 2 LASTPIN (-1025 2550) $PN 2
J 2
(-1035 2560);
DISPLAY 0.808511 (-1035 2560);
FORCEPROP 2 LAST VALUE DIFF BUS_0.22UF
J 2
(-1100 2550);
DISPLAY 0.553191 (-1100 2550);
FORCEPROP 1 LAST CDS_LMAN_SYM_OUTLINE -25,50,25,-50
J 2
(-950 2550);
DISPLAY 0.468085 (-950 2550);
PAINT GREEN (-950 2550);
DISPLAY INVISIBLE (-950 2550);
FORCEPROP 2 LAST CDS_LIB pure_quanta
J 2
(-950 2550);
DISPLAY INVISIBLE (-950 2550);
FORCEPROP 1 LAST PIN_NAMES_ROTATE TRUE
J 2
(-950 2550);
DISPLAY 0.489362 (-950 2550);
PAINT GREEN (-950 2550);
DISPLAY INVISIBLE (-950 2550);
FORCEPROP 2 LAST VOLTAGE 6.3V
J 2
(-1300 2600);
DISPLAY 0.553191 (-1300 2600);
DISPLAY INVISIBLE (-1300 2600);
FORCEPROP 1 LAST MATERIAL X6S
J 2
(-941 2629);
DISPLAY 0.574468 (-941 2629);
PAINT GREEN (-941 2629);
DISPLAY INVISIBLE (-941 2629);
FORCEPROP 2 LAST PACK_TYPE C0201
J 2
(-1125 2600);
DISPLAY 0.553191 (-1125 2600);
DISPLAY INVISIBLE (-1125 2600);
FORCEPROP 2 LAST TOLERANCE 20%
J 2
(-1025 2600);
DISPLAY 0.553191 (-1025 2600);
DISPLAY INVISIBLE (-1025 2600);
FORCEPROP 1 LAST PART_NUMBER SP_CH4221MEE01
J 2
(-1066 2638);
DISPLAY 0.574468 (-1066 2638);
PAINT GREEN (-1066 2638);
DISPLAY INVISIBLE (-1066 2638);
FORCEPROP 1 LAST LOCATION C721
J 0
(-700 2625);
DISPLAY 1.021277 (-700 2625);
DISPLAY INVISIBLE (-700 2625);
FORCEPROP 1 LAST PATH I278
J 2
(-950 2550);
DISPLAY 0.723404 (-950 2550);
DISPLAY INVISIBLE (-950 2550);
FORCEADD Q_CAP_DIFFBUS..2
R 2
(-950 2600);
FORCEPROP 1 LAST LOCATION C720
J 2
(-716 2617);
DISPLAY 0.723404 (-716 2617);
PAINT GREEN (-716 2617);
FORCEPROP 2 LAST $SEC 1
J 2
(-775 2675);
DISPLAY 0.680851 (-775 2675);
PAINT MONO (-775 2675);
DISPLAY INVISIBLE (-775 2675);
FORCEPROP 2 LAST CDS_SEC 1
J 2
(-775 2675);
DISPLAY 0.680851 (-775 2675);
DISPLAY INVISIBLE (-775 2675);
FORCEPROP 2 LASTPIN (-875 2600) $PN 1
J 0
(-865 2610);
DISPLAY 0.808511 (-865 2610);
FORCEPROP 2 LASTPIN (-1025 2600) $PN 2
J 2
(-1035 2610);
DISPLAY 0.808511 (-1035 2610);
FORCEPROP 2 LAST VALUE DIFF BUS_0.22UF
J 2
(-1100 2600);
DISPLAY 0.553191 (-1100 2600);
FORCEPROP 1 LAST CDS_LMAN_SYM_OUTLINE -25,50,25,-50
J 2
(-950 2600);
DISPLAY 0.468085 (-950 2600);
PAINT GREEN (-950 2600);
DISPLAY INVISIBLE (-950 2600);
FORCEPROP 2 LAST CDS_LIB pure_quanta
J 2
(-950 2600);
DISPLAY INVISIBLE (-950 2600);
FORCEPROP 1 LAST PIN_NAMES_ROTATE TRUE
J 2
(-950 2600);
DISPLAY 0.489362 (-950 2600);
PAINT GREEN (-950 2600);
DISPLAY INVISIBLE (-950 2600);
FORCEPROP 2 LAST VOLTAGE 6.3V
J 2
(-1300 2650);
DISPLAY 0.553191 (-1300 2650);
DISPLAY INVISIBLE (-1300 2650);
FORCEPROP 1 LAST MATERIAL X6S
J 2
(-941 2679);
DISPLAY 0.574468 (-941 2679);
PAINT GREEN (-941 2679);
DISPLAY INVISIBLE (-941 2679);
FORCEPROP 2 LAST PACK_TYPE C0201
J 2
(-1125 2650);
DISPLAY 0.553191 (-1125 2650);
DISPLAY INVISIBLE (-1125 2650);
FORCEPROP 2 LAST TOLERANCE 20%
J 2
(-1025 2650);
DISPLAY 0.553191 (-1025 2650);
DISPLAY INVISIBLE (-1025 2650);
FORCEPROP 1 LAST PART_NUMBER SP_CH4221MEE01
J 2
(-1066 2688);
DISPLAY 0.574468 (-1066 2688);
PAINT GREEN (-1066 2688);
DISPLAY INVISIBLE (-1066 2688);
FORCEPROP 1 LAST LOCATION C720
J 0
(-700 2675);
DISPLAY 1.021277 (-700 2675);
DISPLAY INVISIBLE (-700 2675);
FORCEPROP 1 LAST PATH I279
J 2
(-950 2600);
DISPLAY 0.723404 (-950 2600);
DISPLAY INVISIBLE (-950 2600);
FORCEADD Q_CAP_DIFFBUS..2
R 2
(-950 2750);
FORCEPROP 1 LAST LOCATION C719
J 2
(-716 2767);
DISPLAY 0.723404 (-716 2767);
PAINT GREEN (-716 2767);
FORCEPROP 2 LAST $SEC 1
J 2
(-775 2825);
DISPLAY 0.680851 (-775 2825);
PAINT MONO (-775 2825);
DISPLAY INVISIBLE (-775 2825);
FORCEPROP 2 LAST CDS_SEC 1
J 2
(-775 2825);
DISPLAY 0.680851 (-775 2825);
DISPLAY INVISIBLE (-775 2825);
FORCEPROP 2 LASTPIN (-875 2750) $PN 1
J 0
(-865 2760);
DISPLAY 0.808511 (-865 2760);
FORCEPROP 2 LASTPIN (-1025 2750) $PN 2
J 2
(-1035 2760);
DISPLAY 0.808511 (-1035 2760);
FORCEPROP 2 LAST VALUE DIFF BUS_0.22UF
J 2
(-1100 2750);
DISPLAY 0.553191 (-1100 2750);
FORCEPROP 2 LAST CDS_LIB pure_quanta
J 2
(-950 2750);
DISPLAY INVISIBLE (-950 2750);
FORCEPROP 1 LAST CDS_LMAN_SYM_OUTLINE -25,50,25,-50
J 2
(-950 2750);
DISPLAY 0.468085 (-950 2750);
PAINT GREEN (-950 2750);
DISPLAY INVISIBLE (-950 2750);
FORCEPROP 1 LAST PIN_NAMES_ROTATE TRUE
J 2
(-950 2750);
DISPLAY 0.489362 (-950 2750);
PAINT GREEN (-950 2750);
DISPLAY INVISIBLE (-950 2750);
FORCEPROP 2 LAST VOLTAGE 6.3V
J 2
(-1300 2800);
DISPLAY 0.553191 (-1300 2800);
DISPLAY INVISIBLE (-1300 2800);
FORCEPROP 1 LAST MATERIAL X6S
J 2
(-941 2829);
DISPLAY 0.574468 (-941 2829);
PAINT GREEN (-941 2829);
DISPLAY INVISIBLE (-941 2829);
FORCEPROP 2 LAST PACK_TYPE C0201
J 2
(-1125 2800);
DISPLAY 0.553191 (-1125 2800);
DISPLAY INVISIBLE (-1125 2800);
FORCEPROP 2 LAST TOLERANCE 20%
J 2
(-1025 2800);
DISPLAY 0.553191 (-1025 2800);
DISPLAY INVISIBLE (-1025 2800);
FORCEPROP 1 LAST PART_NUMBER SP_CH4221MEE01
J 2
(-1066 2838);
DISPLAY 0.574468 (-1066 2838);
PAINT GREEN (-1066 2838);
DISPLAY INVISIBLE (-1066 2838);
FORCEPROP 1 LAST LOCATION C719
J 0
(-700 2825);
DISPLAY 1.021277 (-700 2825);
DISPLAY INVISIBLE (-700 2825);
FORCEPROP 1 LAST PATH I280
J 2
(-950 2750);
DISPLAY 0.723404 (-950 2750);
DISPLAY INVISIBLE (-950 2750);
FORCEADD Q_CAP_DIFFBUS..2
R 2
(-950 2800);
FORCEPROP 1 LAST LOCATION C718
J 2
(-716 2817);
DISPLAY 0.723404 (-716 2817);
PAINT GREEN (-716 2817);
FORCEPROP 2 LAST $SEC 1
J 2
(-775 2875);
DISPLAY 0.680851 (-775 2875);
PAINT MONO (-775 2875);
DISPLAY INVISIBLE (-775 2875);
FORCEPROP 2 LAST CDS_SEC 1
J 2
(-775 2875);
DISPLAY 0.680851 (-775 2875);
DISPLAY INVISIBLE (-775 2875);
FORCEPROP 2 LASTPIN (-875 2800) $PN 1
J 0
(-865 2810);
DISPLAY 0.808511 (-865 2810);
FORCEPROP 2 LASTPIN (-1025 2800) $PN 2
J 2
(-1035 2810);
DISPLAY 0.808511 (-1035 2810);
FORCEPROP 2 LAST VALUE DIFF BUS_0.22UF
J 2
(-1100 2800);
DISPLAY 0.553191 (-1100 2800);
FORCEPROP 2 LAST CDS_LIB pure_quanta
J 2
(-950 2800);
DISPLAY INVISIBLE (-950 2800);
FORCEPROP 1 LAST CDS_LMAN_SYM_OUTLINE -25,50,25,-50
J 2
(-950 2800);
DISPLAY 0.468085 (-950 2800);
PAINT GREEN (-950 2800);
DISPLAY INVISIBLE (-950 2800);
FORCEPROP 1 LAST PIN_NAMES_ROTATE TRUE
J 2
(-950 2800);
DISPLAY 0.489362 (-950 2800);
PAINT GREEN (-950 2800);
DISPLAY INVISIBLE (-950 2800);
FORCEPROP 2 LAST VOLTAGE 6.3V
J 2
(-1300 2850);
DISPLAY 0.553191 (-1300 2850);
DISPLAY INVISIBLE (-1300 2850);
FORCEPROP 1 LAST MATERIAL X6S
J 2
(-941 2879);
DISPLAY 0.574468 (-941 2879);
PAINT GREEN (-941 2879);
DISPLAY INVISIBLE (-941 2879);
FORCEPROP 2 LAST PACK_TYPE C0201
J 2
(-1125 2850);
DISPLAY 0.553191 (-1125 2850);
DISPLAY INVISIBLE (-1125 2850);
FORCEPROP 2 LAST TOLERANCE 20%
J 2
(-1025 2850);
DISPLAY 0.553191 (-1025 2850);
DISPLAY INVISIBLE (-1025 2850);
FORCEPROP 1 LAST PART_NUMBER SP_CH4221MEE01
J 2
(-1066 2888);
DISPLAY 0.574468 (-1066 2888);
PAINT GREEN (-1066 2888);
DISPLAY INVISIBLE (-1066 2888);
FORCEPROP 1 LAST LOCATION C718
J 0
(-700 2875);
DISPLAY 1.021277 (-700 2875);
DISPLAY INVISIBLE (-700 2875);
FORCEPROP 1 LAST PATH I281
J 2
(-950 2800);
DISPLAY 0.723404 (-950 2800);
DISPLAY INVISIBLE (-950 2800);
FORCEADD Q_CAP_DIFFBUS..2
R 2
(-950 2950);
FORCEPROP 1 LAST LOCATION C717
J 2
(-716 2967);
DISPLAY 0.723404 (-716 2967);
PAINT GREEN (-716 2967);
FORCEPROP 2 LAST $SEC 1
J 2
(-775 3025);
DISPLAY 0.680851 (-775 3025);
PAINT MONO (-775 3025);
DISPLAY INVISIBLE (-775 3025);
FORCEPROP 2 LAST CDS_SEC 1
J 2
(-775 3025);
DISPLAY 0.680851 (-775 3025);
DISPLAY INVISIBLE (-775 3025);
FORCEPROP 2 LASTPIN (-875 2950) $PN 1
J 0
(-865 2960);
DISPLAY 0.808511 (-865 2960);
FORCEPROP 2 LASTPIN (-1025 2950) $PN 2
J 2
(-1035 2960);
DISPLAY 0.808511 (-1035 2960);
FORCEPROP 2 LAST VALUE DIFF BUS_0.22UF
J 2
(-1100 2950);
DISPLAY 0.553191 (-1100 2950);
FORCEPROP 1 LAST CDS_LMAN_SYM_OUTLINE -25,50,25,-50
J 2
(-950 2950);
DISPLAY 0.468085 (-950 2950);
PAINT GREEN (-950 2950);
DISPLAY INVISIBLE (-950 2950);
FORCEPROP 2 LAST CDS_LIB pure_quanta
J 2
(-950 2950);
DISPLAY INVISIBLE (-950 2950);
FORCEPROP 1 LAST PIN_NAMES_ROTATE TRUE
J 2
(-950 2950);
DISPLAY 0.489362 (-950 2950);
PAINT GREEN (-950 2950);
DISPLAY INVISIBLE (-950 2950);
FORCEPROP 2 LAST VOLTAGE 6.3V
J 2
(-1300 3000);
DISPLAY 0.553191 (-1300 3000);
DISPLAY INVISIBLE (-1300 3000);
FORCEPROP 1 LAST MATERIAL X6S
J 2
(-941 3029);
DISPLAY 0.574468 (-941 3029);
PAINT GREEN (-941 3029);
DISPLAY INVISIBLE (-941 3029);
FORCEPROP 2 LAST PACK_TYPE C0201
J 2
(-1125 3000);
DISPLAY 0.553191 (-1125 3000);
DISPLAY INVISIBLE (-1125 3000);
FORCEPROP 2 LAST TOLERANCE 20%
J 2
(-1025 3000);
DISPLAY 0.553191 (-1025 3000);
DISPLAY INVISIBLE (-1025 3000);
FORCEPROP 1 LAST PART_NUMBER SP_CH4221MEE01
J 2
(-1066 3038);
DISPLAY 0.574468 (-1066 3038);
PAINT GREEN (-1066 3038);
DISPLAY INVISIBLE (-1066 3038);
FORCEPROP 1 LAST LOCATION C717
J 0
(-700 3025);
DISPLAY 1.021277 (-700 3025);
DISPLAY INVISIBLE (-700 3025);
FORCEPROP 1 LAST PATH I282
J 2
(-950 2950);
DISPLAY 0.723404 (-950 2950);
DISPLAY INVISIBLE (-950 2950);
FORCEADD Q_CAP_DIFFBUS..2
R 2
(-950 3000);
FORCEPROP 1 LAST LOCATION C716
J 2
(-716 3017);
DISPLAY 0.723404 (-716 3017);
PAINT GREEN (-716 3017);
FORCEPROP 2 LAST $SEC 1
J 2
(-775 3075);
DISPLAY 0.680851 (-775 3075);
PAINT MONO (-775 3075);
DISPLAY INVISIBLE (-775 3075);
FORCEPROP 2 LAST CDS_SEC 1
J 2
(-775 3075);
DISPLAY 0.680851 (-775 3075);
DISPLAY INVISIBLE (-775 3075);
FORCEPROP 2 LASTPIN (-875 3000) $PN 1
J 0
(-865 3010);
DISPLAY 0.808511 (-865 3010);
FORCEPROP 2 LASTPIN (-1025 3000) $PN 2
J 2
(-1035 3010);
DISPLAY 0.808511 (-1035 3010);
FORCEPROP 2 LAST VALUE DIFF BUS_0.22UF
J 2
(-1100 3000);
DISPLAY 0.553191 (-1100 3000);
FORCEPROP 1 LAST CDS_LMAN_SYM_OUTLINE -25,50,25,-50
J 2
(-950 3000);
DISPLAY 0.468085 (-950 3000);
PAINT GREEN (-950 3000);
DISPLAY INVISIBLE (-950 3000);
FORCEPROP 2 LAST CDS_LIB pure_quanta
J 2
(-950 3000);
DISPLAY INVISIBLE (-950 3000);
FORCEPROP 1 LAST PIN_NAMES_ROTATE TRUE
J 2
(-950 3000);
DISPLAY 0.489362 (-950 3000);
PAINT GREEN (-950 3000);
DISPLAY INVISIBLE (-950 3000);
FORCEPROP 2 LAST VOLTAGE 6.3V
J 2
(-1300 3050);
DISPLAY 0.553191 (-1300 3050);
DISPLAY INVISIBLE (-1300 3050);
FORCEPROP 1 LAST MATERIAL X6S
J 2
(-941 3079);
DISPLAY 0.574468 (-941 3079);
PAINT GREEN (-941 3079);
DISPLAY INVISIBLE (-941 3079);
FORCEPROP 2 LAST PACK_TYPE C0201
J 2
(-1125 3050);
DISPLAY 0.553191 (-1125 3050);
DISPLAY INVISIBLE (-1125 3050);
FORCEPROP 2 LAST TOLERANCE 20%
J 2
(-1025 3050);
DISPLAY 0.553191 (-1025 3050);
DISPLAY INVISIBLE (-1025 3050);
FORCEPROP 1 LAST PART_NUMBER SP_CH4221MEE01
J 2
(-1066 3088);
DISPLAY 0.574468 (-1066 3088);
PAINT GREEN (-1066 3088);
DISPLAY INVISIBLE (-1066 3088);
FORCEPROP 1 LAST LOCATION C716
J 0
(-700 3075);
DISPLAY 1.021277 (-700 3075);
DISPLAY INVISIBLE (-700 3075);
FORCEPROP 1 LAST PATH I283
J 2
(-950 3000);
DISPLAY 0.723404 (-950 3000);
DISPLAY INVISIBLE (-950 3000);
FORCEADD TAP..1
(-400 2200);
FORCEPROP 3 LASTPIN (-450 2200) SIG_NAME P5E_CPU1_P1_TX_C_DN<8>
J 0
(-440 2210);
DISPLAY 0.659574 (-440 2210);
PAINT MONO (-440 2210);
DISPLAY INVISIBLE (-440 2210);
FORCEPROP 1 LASTPIN (-450 2200) BN 8
J 0
(-462 2208);
DISPLAY 0.680851 (-462 2208);
PAINT GREEN (-462 2208);
FORCEPROP 2 LAST CDS_LIB standard
J 0
(-400 2200);
DISPLAY INVISIBLE (-400 2200);
FORCEPROP 1 LAST BODY_TYPE PLUMBING
J 0
(-400 2250);
DISPLAY 0.872340 (-400 2250);
PAINT GREEN (-400 2250);
DISPLAY INVISIBLE (-400 2250);
FORCEPROP 1 LAST HDL_TAP TRUE
J 0
(-75 2075);
DISPLAY 0.872340 (-75 2075);
DISPLAY INVISIBLE (-75 2075);
FORCEPROP 1 LAST PATH I284
J 0
(-402 2200);
DISPLAY 0.872340 (-402 2200);
PAINT GREEN (-402 2200);
DISPLAY INVISIBLE (-402 2200);
FORCEADD TAP..1
(-400 2400);
FORCEPROP 3 LASTPIN (-450 2400) SIG_NAME P5E_CPU1_P1_TX_C_DN<9>
J 0
(-440 2410);
DISPLAY 0.659574 (-440 2410);
PAINT MONO (-440 2410);
DISPLAY INVISIBLE (-440 2410);
FORCEPROP 1 LASTPIN (-450 2400) BN 9
J 0
(-462 2408);
DISPLAY 0.680851 (-462 2408);
PAINT GREEN (-462 2408);
FORCEPROP 2 LAST CDS_LIB standard
J 0
(-400 2400);
DISPLAY INVISIBLE (-400 2400);
FORCEPROP 1 LAST BODY_TYPE PLUMBING
J 0
(-400 2450);
DISPLAY 0.872340 (-400 2450);
PAINT GREEN (-400 2450);
DISPLAY INVISIBLE (-400 2450);
FORCEPROP 1 LAST HDL_TAP TRUE
J 0
(-75 2275);
DISPLAY 0.872340 (-75 2275);
DISPLAY INVISIBLE (-75 2275);
FORCEPROP 1 LAST PATH I285
J 0
(-402 2400);
DISPLAY 0.872340 (-402 2400);
PAINT GREEN (-402 2400);
DISPLAY INVISIBLE (-402 2400);
FORCEADD TAP..1
(-200 2150);
FORCEPROP 3 LASTPIN (-250 2150) SIG_NAME P5E_CPU1_P1_TX_C_DP<8>
J 0
(-240 2160);
DISPLAY 0.659574 (-240 2160);
PAINT MONO (-240 2160);
DISPLAY INVISIBLE (-240 2160);
FORCEPROP 1 LASTPIN (-250 2150) BN 8
J 0
(-262 2158);
DISPLAY 0.680851 (-262 2158);
PAINT GREEN (-262 2158);
FORCEPROP 2 LAST CDS_LIB standard
J 0
(-200 2150);
DISPLAY INVISIBLE (-200 2150);
FORCEPROP 1 LAST BODY_TYPE PLUMBING
J 0
(-200 2200);
DISPLAY 0.872340 (-200 2200);
PAINT GREEN (-200 2200);
DISPLAY INVISIBLE (-200 2200);
FORCEPROP 1 LAST HDL_TAP TRUE
J 0
(125 2025);
DISPLAY 0.872340 (125 2025);
DISPLAY INVISIBLE (125 2025);
FORCEPROP 1 LAST PATH I286
J 0
(-202 2150);
DISPLAY 0.872340 (-202 2150);
PAINT GREEN (-202 2150);
DISPLAY INVISIBLE (-202 2150);
FORCEADD TAP..1
(-200 2350);
FORCEPROP 3 LASTPIN (-250 2350) SIG_NAME P5E_CPU1_P1_TX_C_DP<9>
J 0
(-240 2360);
DISPLAY 0.659574 (-240 2360);
PAINT MONO (-240 2360);
DISPLAY INVISIBLE (-240 2360);
FORCEPROP 1 LASTPIN (-250 2350) BN 9
J 0
(-262 2358);
DISPLAY 0.680851 (-262 2358);
PAINT GREEN (-262 2358);
FORCEPROP 2 LAST CDS_LIB standard
J 0
(-200 2350);
DISPLAY INVISIBLE (-200 2350);
FORCEPROP 1 LAST BODY_TYPE PLUMBING
J 0
(-200 2400);
DISPLAY 0.872340 (-200 2400);
PAINT GREEN (-200 2400);
DISPLAY INVISIBLE (-200 2400);
FORCEPROP 1 LAST HDL_TAP TRUE
J 0
(125 2225);
DISPLAY 0.872340 (125 2225);
DISPLAY INVISIBLE (125 2225);
FORCEPROP 1 LAST PATH I287
J 0
(-202 2350);
DISPLAY 0.872340 (-202 2350);
PAINT GREEN (-202 2350);
DISPLAY INVISIBLE (-202 2350);
FORCEADD TAP..1
(-400 2600);
FORCEPROP 3 LASTPIN (-450 2600) SIG_NAME P5E_CPU1_P1_TX_C_DN<10>
J 0
(-440 2610);
DISPLAY 0.659574 (-440 2610);
PAINT MONO (-440 2610);
DISPLAY INVISIBLE (-440 2610);
FORCEPROP 1 LASTPIN (-450 2600) BN 10
J 0
(-462 2608);
DISPLAY 0.680851 (-462 2608);
PAINT GREEN (-462 2608);
FORCEPROP 2 LAST CDS_LIB standard
J 0
(-400 2600);
DISPLAY INVISIBLE (-400 2600);
FORCEPROP 1 LAST BODY_TYPE PLUMBING
J 0
(-400 2650);
DISPLAY 0.872340 (-400 2650);
PAINT GREEN (-400 2650);
DISPLAY INVISIBLE (-400 2650);
FORCEPROP 1 LAST HDL_TAP TRUE
J 0
(-75 2475);
DISPLAY 0.872340 (-75 2475);
DISPLAY INVISIBLE (-75 2475);
FORCEPROP 1 LAST PATH I288
J 0
(-402 2600);
DISPLAY 0.872340 (-402 2600);
PAINT GREEN (-402 2600);
DISPLAY INVISIBLE (-402 2600);
FORCEADD TAP..1
(-400 3000);
FORCEPROP 3 LASTPIN (-450 3000) SIG_NAME P5E_CPU1_P1_TX_C_DN<12>
J 0
(-440 3010);
DISPLAY 0.659574 (-440 3010);
PAINT MONO (-440 3010);
DISPLAY INVISIBLE (-440 3010);
FORCEPROP 1 LASTPIN (-450 3000) BN 12
J 0
(-462 3008);
DISPLAY 0.680851 (-462 3008);
PAINT GREEN (-462 3008);
FORCEPROP 2 LAST CDS_LIB standard
J 0
(-400 3000);
DISPLAY INVISIBLE (-400 3000);
FORCEPROP 1 LAST BODY_TYPE PLUMBING
J 0
(-400 3050);
DISPLAY 0.872340 (-400 3050);
PAINT GREEN (-400 3050);
DISPLAY INVISIBLE (-400 3050);
FORCEPROP 1 LAST HDL_TAP TRUE
J 0
(-75 2875);
DISPLAY 0.872340 (-75 2875);
DISPLAY INVISIBLE (-75 2875);
FORCEPROP 1 LAST PATH I289
J 0
(-402 3000);
DISPLAY 0.872340 (-402 3000);
PAINT GREEN (-402 3000);
DISPLAY INVISIBLE (-402 3000);
FORCEADD TAP..1
(-400 2800);
FORCEPROP 3 LASTPIN (-450 2800) SIG_NAME P5E_CPU1_P1_TX_C_DN<11>
J 0
(-440 2810);
DISPLAY 0.659574 (-440 2810);
PAINT MONO (-440 2810);
DISPLAY INVISIBLE (-440 2810);
FORCEPROP 1 LASTPIN (-450 2800) BN 11
J 0
(-462 2808);
DISPLAY 0.680851 (-462 2808);
PAINT GREEN (-462 2808);
FORCEPROP 2 LAST CDS_LIB standard
J 0
(-400 2800);
DISPLAY INVISIBLE (-400 2800);
FORCEPROP 1 LAST BODY_TYPE PLUMBING
J 0
(-400 2850);
DISPLAY 0.872340 (-400 2850);
PAINT GREEN (-400 2850);
DISPLAY INVISIBLE (-400 2850);
FORCEPROP 1 LAST HDL_TAP TRUE
J 0
(-75 2675);
DISPLAY 0.872340 (-75 2675);
DISPLAY INVISIBLE (-75 2675);
FORCEPROP 1 LAST PATH I290
J 0
(-402 2800);
DISPLAY 0.872340 (-402 2800);
PAINT GREEN (-402 2800);
DISPLAY INVISIBLE (-402 2800);
FORCEADD TAP..1
(-200 2550);
FORCEPROP 3 LASTPIN (-250 2550) SIG_NAME P5E_CPU1_P1_TX_C_DP<10>
J 0
(-240 2560);
DISPLAY 0.659574 (-240 2560);
PAINT MONO (-240 2560);
DISPLAY INVISIBLE (-240 2560);
FORCEPROP 1 LASTPIN (-250 2550) BN 10
J 0
(-262 2558);
DISPLAY 0.680851 (-262 2558);
PAINT GREEN (-262 2558);
FORCEPROP 2 LAST CDS_LIB standard
J 0
(-200 2550);
DISPLAY INVISIBLE (-200 2550);
FORCEPROP 1 LAST BODY_TYPE PLUMBING
J 0
(-200 2600);
DISPLAY 0.872340 (-200 2600);
PAINT GREEN (-200 2600);
DISPLAY INVISIBLE (-200 2600);
FORCEPROP 1 LAST HDL_TAP TRUE
J 0
(125 2425);
DISPLAY 0.872340 (125 2425);
DISPLAY INVISIBLE (125 2425);
FORCEPROP 1 LAST PATH I291
J 0
(-202 2550);
DISPLAY 0.872340 (-202 2550);
PAINT GREEN (-202 2550);
DISPLAY INVISIBLE (-202 2550);
FORCEADD TAP..1
(-200 2750);
FORCEPROP 3 LASTPIN (-250 2750) SIG_NAME P5E_CPU1_P1_TX_C_DP<11>
J 0
(-240 2760);
DISPLAY 0.659574 (-240 2760);
PAINT MONO (-240 2760);
DISPLAY INVISIBLE (-240 2760);
FORCEPROP 1 LASTPIN (-250 2750) BN 11
J 0
(-262 2758);
DISPLAY 0.680851 (-262 2758);
PAINT GREEN (-262 2758);
FORCEPROP 2 LAST CDS_LIB standard
J 0
(-200 2750);
DISPLAY INVISIBLE (-200 2750);
FORCEPROP 1 LAST BODY_TYPE PLUMBING
J 0
(-200 2800);
DISPLAY 0.872340 (-200 2800);
PAINT GREEN (-200 2800);
DISPLAY INVISIBLE (-200 2800);
FORCEPROP 1 LAST HDL_TAP TRUE
J 0
(125 2625);
DISPLAY 0.872340 (125 2625);
DISPLAY INVISIBLE (125 2625);
FORCEPROP 1 LAST PATH I292
J 0
(-202 2750);
DISPLAY 0.872340 (-202 2750);
PAINT GREEN (-202 2750);
DISPLAY INVISIBLE (-202 2750);
FORCEADD TAP..1
(-200 2950);
FORCEPROP 3 LASTPIN (-250 2950) SIG_NAME P5E_CPU1_P1_TX_C_DP<12>
J 0
(-240 2960);
DISPLAY 0.659574 (-240 2960);
PAINT MONO (-240 2960);
DISPLAY INVISIBLE (-240 2960);
FORCEPROP 1 LASTPIN (-250 2950) BN 12
J 0
(-262 2958);
DISPLAY 0.680851 (-262 2958);
PAINT GREEN (-262 2958);
FORCEPROP 2 LAST CDS_LIB standard
J 0
(-200 2950);
DISPLAY INVISIBLE (-200 2950);
FORCEPROP 1 LAST BODY_TYPE PLUMBING
J 0
(-200 3000);
DISPLAY 0.872340 (-200 3000);
PAINT GREEN (-200 3000);
DISPLAY INVISIBLE (-200 3000);
FORCEPROP 1 LAST HDL_TAP TRUE
J 0
(125 2825);
DISPLAY 0.872340 (125 2825);
DISPLAY INVISIBLE (125 2825);
FORCEPROP 1 LAST PATH I293
J 0
(-202 2950);
DISPLAY 0.872340 (-202 2950);
PAINT GREEN (-202 2950);
DISPLAY INVISIBLE (-202 2950);
FORCEADD Q_CAP_DIFFBUS..2
R 2
(-950 3150);
FORCEPROP 1 LAST LOCATION C715
J 2
(-716 3167);
DISPLAY 0.723404 (-716 3167);
PAINT GREEN (-716 3167);
FORCEPROP 2 LAST $SEC 1
J 2
(-775 3225);
DISPLAY 0.680851 (-775 3225);
PAINT MONO (-775 3225);
DISPLAY INVISIBLE (-775 3225);
FORCEPROP 2 LAST CDS_SEC 1
J 2
(-775 3225);
DISPLAY 0.680851 (-775 3225);
DISPLAY INVISIBLE (-775 3225);
FORCEPROP 2 LASTPIN (-875 3150) $PN 1
J 0
(-865 3160);
DISPLAY 0.808511 (-865 3160);
FORCEPROP 2 LASTPIN (-1025 3150) $PN 2
J 2
(-1035 3160);
DISPLAY 0.808511 (-1035 3160);
FORCEPROP 2 LAST VALUE DIFF BUS_0.22UF
J 2
(-1100 3150);
DISPLAY 0.553191 (-1100 3150);
FORCEPROP 1 LAST CDS_LMAN_SYM_OUTLINE -25,50,25,-50
J 2
(-950 3150);
DISPLAY 0.468085 (-950 3150);
PAINT GREEN (-950 3150);
DISPLAY INVISIBLE (-950 3150);
FORCEPROP 2 LAST CDS_LIB pure_quanta
J 2
(-950 3150);
DISPLAY INVISIBLE (-950 3150);
FORCEPROP 1 LAST PIN_NAMES_ROTATE TRUE
J 2
(-950 3150);
DISPLAY 0.489362 (-950 3150);
PAINT GREEN (-950 3150);
DISPLAY INVISIBLE (-950 3150);
FORCEPROP 2 LAST VOLTAGE 6.3V
J 2
(-1300 3200);
DISPLAY 0.553191 (-1300 3200);
DISPLAY INVISIBLE (-1300 3200);
FORCEPROP 1 LAST MATERIAL X6S
J 2
(-941 3229);
DISPLAY 0.574468 (-941 3229);
PAINT GREEN (-941 3229);
DISPLAY INVISIBLE (-941 3229);
FORCEPROP 2 LAST PACK_TYPE C0201
J 2
(-1125 3200);
DISPLAY 0.553191 (-1125 3200);
DISPLAY INVISIBLE (-1125 3200);
FORCEPROP 2 LAST TOLERANCE 20%
J 2
(-1025 3200);
DISPLAY 0.553191 (-1025 3200);
DISPLAY INVISIBLE (-1025 3200);
FORCEPROP 1 LAST PART_NUMBER SP_CH4221MEE01
J 2
(-1066 3238);
DISPLAY 0.574468 (-1066 3238);
PAINT GREEN (-1066 3238);
DISPLAY INVISIBLE (-1066 3238);
FORCEPROP 1 LAST LOCATION C715
J 0
(-700 3225);
DISPLAY 1.021277 (-700 3225);
DISPLAY INVISIBLE (-700 3225);
FORCEPROP 1 LAST PATH I294
J 2
(-950 3150);
DISPLAY 0.723404 (-950 3150);
DISPLAY INVISIBLE (-950 3150);
FORCEADD Q_CAP_DIFFBUS..2
R 2
(-950 3200);
FORCEPROP 1 LAST LOCATION C714
J 2
(-716 3217);
DISPLAY 0.723404 (-716 3217);
PAINT GREEN (-716 3217);
FORCEPROP 2 LAST $SEC 1
J 2
(-775 3275);
DISPLAY 0.680851 (-775 3275);
PAINT MONO (-775 3275);
DISPLAY INVISIBLE (-775 3275);
FORCEPROP 2 LAST CDS_SEC 1
J 2
(-775 3275);
DISPLAY 0.680851 (-775 3275);
DISPLAY INVISIBLE (-775 3275);
FORCEPROP 2 LASTPIN (-875 3200) $PN 1
J 0
(-865 3210);
DISPLAY 0.808511 (-865 3210);
FORCEPROP 2 LASTPIN (-1025 3200) $PN 2
J 2
(-1035 3210);
DISPLAY 0.808511 (-1035 3210);
FORCEPROP 2 LAST VALUE DIFF BUS_0.22UF
J 2
(-1100 3200);
DISPLAY 0.553191 (-1100 3200);
FORCEPROP 1 LAST CDS_LMAN_SYM_OUTLINE -25,50,25,-50
J 2
(-950 3200);
DISPLAY 0.468085 (-950 3200);
PAINT GREEN (-950 3200);
DISPLAY INVISIBLE (-950 3200);
FORCEPROP 2 LAST CDS_LIB pure_quanta
J 2
(-950 3200);
DISPLAY INVISIBLE (-950 3200);
FORCEPROP 1 LAST PIN_NAMES_ROTATE TRUE
J 2
(-950 3200);
DISPLAY 0.489362 (-950 3200);
PAINT GREEN (-950 3200);
DISPLAY INVISIBLE (-950 3200);
FORCEPROP 2 LAST VOLTAGE 6.3V
J 2
(-1300 3250);
DISPLAY 0.553191 (-1300 3250);
DISPLAY INVISIBLE (-1300 3250);
FORCEPROP 1 LAST MATERIAL X6S
J 2
(-941 3279);
DISPLAY 0.574468 (-941 3279);
PAINT GREEN (-941 3279);
DISPLAY INVISIBLE (-941 3279);
FORCEPROP 2 LAST PACK_TYPE C0201
J 2
(-1125 3250);
DISPLAY 0.553191 (-1125 3250);
DISPLAY INVISIBLE (-1125 3250);
FORCEPROP 2 LAST TOLERANCE 20%
J 2
(-1025 3250);
DISPLAY 0.553191 (-1025 3250);
DISPLAY INVISIBLE (-1025 3250);
FORCEPROP 1 LAST PART_NUMBER SP_CH4221MEE01
J 2
(-1066 3288);
DISPLAY 0.574468 (-1066 3288);
PAINT GREEN (-1066 3288);
DISPLAY INVISIBLE (-1066 3288);
FORCEPROP 1 LAST LOCATION C714
J 0
(-700 3275);
DISPLAY 1.021277 (-700 3275);
DISPLAY INVISIBLE (-700 3275);
FORCEPROP 1 LAST PATH I295
J 2
(-950 3200);
DISPLAY 0.723404 (-950 3200);
DISPLAY INVISIBLE (-950 3200);
FORCEADD Q_CAP_DIFFBUS..2
R 2
(-950 3400);
FORCEPROP 1 LAST LOCATION C712
J 2
(-716 3417);
DISPLAY 0.723404 (-716 3417);
PAINT GREEN (-716 3417);
FORCEPROP 2 LAST $SEC 1
J 2
(-775 3475);
DISPLAY 0.680851 (-775 3475);
PAINT MONO (-775 3475);
DISPLAY INVISIBLE (-775 3475);
FORCEPROP 2 LAST CDS_SEC 1
J 2
(-775 3475);
DISPLAY 0.680851 (-775 3475);
DISPLAY INVISIBLE (-775 3475);
FORCEPROP 2 LASTPIN (-875 3400) $PN 1
J 0
(-865 3410);
DISPLAY 0.808511 (-865 3410);
FORCEPROP 2 LASTPIN (-1025 3400) $PN 2
J 2
(-1035 3410);
DISPLAY 0.808511 (-1035 3410);
FORCEPROP 2 LAST VALUE DIFF BUS_0.22UF
J 2
(-1100 3400);
DISPLAY 0.553191 (-1100 3400);
FORCEPROP 1 LAST CDS_LMAN_SYM_OUTLINE -25,50,25,-50
J 2
(-950 3400);
DISPLAY 0.468085 (-950 3400);
PAINT GREEN (-950 3400);
DISPLAY INVISIBLE (-950 3400);
FORCEPROP 2 LAST CDS_LIB pure_quanta
J 2
(-950 3400);
DISPLAY INVISIBLE (-950 3400);
FORCEPROP 1 LAST PIN_NAMES_ROTATE TRUE
J 2
(-950 3400);
DISPLAY 0.489362 (-950 3400);
PAINT GREEN (-950 3400);
DISPLAY INVISIBLE (-950 3400);
FORCEPROP 2 LAST VOLTAGE 6.3V
J 2
(-1300 3450);
DISPLAY 0.553191 (-1300 3450);
DISPLAY INVISIBLE (-1300 3450);
FORCEPROP 1 LAST MATERIAL X6S
J 2
(-941 3479);
DISPLAY 0.574468 (-941 3479);
PAINT GREEN (-941 3479);
DISPLAY INVISIBLE (-941 3479);
FORCEPROP 2 LAST PACK_TYPE C0201
J 2
(-1125 3450);
DISPLAY 0.553191 (-1125 3450);
DISPLAY INVISIBLE (-1125 3450);
FORCEPROP 2 LAST TOLERANCE 20%
J 2
(-1025 3450);
DISPLAY 0.553191 (-1025 3450);
DISPLAY INVISIBLE (-1025 3450);
FORCEPROP 1 LAST PART_NUMBER SP_CH4221MEE01
J 2
(-1066 3488);
DISPLAY 0.574468 (-1066 3488);
PAINT GREEN (-1066 3488);
DISPLAY INVISIBLE (-1066 3488);
FORCEPROP 1 LAST LOCATION C712
J 0
(-700 3475);
DISPLAY 1.021277 (-700 3475);
DISPLAY INVISIBLE (-700 3475);
FORCEPROP 1 LAST PATH I296
J 2
(-950 3400);
DISPLAY 0.723404 (-950 3400);
DISPLAY INVISIBLE (-950 3400);
FORCEADD Q_CAP_DIFFBUS..2
R 2
(-950 3350);
FORCEPROP 1 LAST LOCATION C713
J 2
(-716 3367);
DISPLAY 0.723404 (-716 3367);
PAINT GREEN (-716 3367);
FORCEPROP 2 LAST $SEC 1
J 2
(-775 3425);
DISPLAY 0.680851 (-775 3425);
PAINT MONO (-775 3425);
DISPLAY INVISIBLE (-775 3425);
FORCEPROP 2 LAST CDS_SEC 1
J 2
(-775 3425);
DISPLAY 0.680851 (-775 3425);
DISPLAY INVISIBLE (-775 3425);
FORCEPROP 2 LASTPIN (-875 3350) $PN 1
J 0
(-865 3360);
DISPLAY 0.808511 (-865 3360);
FORCEPROP 2 LASTPIN (-1025 3350) $PN 2
J 2
(-1035 3360);
DISPLAY 0.808511 (-1035 3360);
FORCEPROP 2 LAST VALUE DIFF BUS_0.22UF
J 2
(-1100 3350);
DISPLAY 0.553191 (-1100 3350);
FORCEPROP 1 LAST CDS_LMAN_SYM_OUTLINE -25,50,25,-50
J 2
(-950 3350);
DISPLAY 0.468085 (-950 3350);
PAINT GREEN (-950 3350);
DISPLAY INVISIBLE (-950 3350);
FORCEPROP 2 LAST CDS_LIB pure_quanta
J 2
(-950 3350);
DISPLAY INVISIBLE (-950 3350);
FORCEPROP 1 LAST PIN_NAMES_ROTATE TRUE
J 2
(-950 3350);
DISPLAY 0.489362 (-950 3350);
PAINT GREEN (-950 3350);
DISPLAY INVISIBLE (-950 3350);
FORCEPROP 2 LAST VOLTAGE 6.3V
J 2
(-1300 3400);
DISPLAY 0.553191 (-1300 3400);
DISPLAY INVISIBLE (-1300 3400);
FORCEPROP 1 LAST MATERIAL X6S
J 2
(-941 3429);
DISPLAY 0.574468 (-941 3429);
PAINT GREEN (-941 3429);
DISPLAY INVISIBLE (-941 3429);
FORCEPROP 2 LAST PACK_TYPE C0201
J 2
(-1125 3400);
DISPLAY 0.553191 (-1125 3400);
DISPLAY INVISIBLE (-1125 3400);
FORCEPROP 2 LAST TOLERANCE 20%
J 2
(-1025 3400);
DISPLAY 0.553191 (-1025 3400);
DISPLAY INVISIBLE (-1025 3400);
FORCEPROP 1 LAST PART_NUMBER SP_CH4221MEE01
J 2
(-1066 3438);
DISPLAY 0.574468 (-1066 3438);
PAINT GREEN (-1066 3438);
DISPLAY INVISIBLE (-1066 3438);
FORCEPROP 1 LAST LOCATION C713
J 0
(-700 3425);
DISPLAY 1.021277 (-700 3425);
DISPLAY INVISIBLE (-700 3425);
FORCEPROP 1 LAST PATH I297
J 2
(-950 3350);
DISPLAY 0.723404 (-950 3350);
DISPLAY INVISIBLE (-950 3350);
FORCEADD Q_CAP_DIFFBUS..2
R 2
(-950 3550);
FORCEPROP 1 LAST LOCATION C711
J 2
(-716 3567);
DISPLAY 0.723404 (-716 3567);
PAINT GREEN (-716 3567);
FORCEPROP 2 LAST $SEC 1
J 2
(-775 3625);
DISPLAY 0.680851 (-775 3625);
PAINT MONO (-775 3625);
DISPLAY INVISIBLE (-775 3625);
FORCEPROP 2 LAST CDS_SEC 1
J 2
(-775 3625);
DISPLAY 0.680851 (-775 3625);
DISPLAY INVISIBLE (-775 3625);
FORCEPROP 2 LASTPIN (-875 3550) $PN 1
J 0
(-865 3560);
DISPLAY 0.808511 (-865 3560);
FORCEPROP 2 LASTPIN (-1025 3550) $PN 2
J 2
(-1035 3560);
DISPLAY 0.808511 (-1035 3560);
FORCEPROP 2 LAST VALUE DIFF BUS_0.22UF
J 2
(-1100 3550);
DISPLAY 0.553191 (-1100 3550);
FORCEPROP 1 LAST CDS_LMAN_SYM_OUTLINE -25,50,25,-50
J 2
(-950 3550);
DISPLAY 0.468085 (-950 3550);
PAINT GREEN (-950 3550);
DISPLAY INVISIBLE (-950 3550);
FORCEPROP 2 LAST CDS_LIB pure_quanta
J 2
(-950 3550);
DISPLAY INVISIBLE (-950 3550);
FORCEPROP 1 LAST PIN_NAMES_ROTATE TRUE
J 2
(-950 3550);
DISPLAY 0.489362 (-950 3550);
PAINT GREEN (-950 3550);
DISPLAY INVISIBLE (-950 3550);
FORCEPROP 2 LAST VOLTAGE 6.3V
J 2
(-1300 3600);
DISPLAY 0.553191 (-1300 3600);
DISPLAY INVISIBLE (-1300 3600);
FORCEPROP 1 LAST MATERIAL X6S
J 2
(-941 3629);
DISPLAY 0.574468 (-941 3629);
PAINT GREEN (-941 3629);
DISPLAY INVISIBLE (-941 3629);
FORCEPROP 2 LAST PACK_TYPE C0201
J 2
(-1125 3600);
DISPLAY 0.553191 (-1125 3600);
DISPLAY INVISIBLE (-1125 3600);
FORCEPROP 2 LAST TOLERANCE 20%
J 2
(-1025 3600);
DISPLAY 0.553191 (-1025 3600);
DISPLAY INVISIBLE (-1025 3600);
FORCEPROP 1 LAST PART_NUMBER SP_CH4221MEE01
J 2
(-1066 3638);
DISPLAY 0.574468 (-1066 3638);
PAINT GREEN (-1066 3638);
DISPLAY INVISIBLE (-1066 3638);
FORCEPROP 1 LAST LOCATION C711
J 0
(-700 3625);
DISPLAY 1.021277 (-700 3625);
DISPLAY INVISIBLE (-700 3625);
FORCEPROP 1 LAST PATH I298
J 2
(-950 3550);
DISPLAY 0.723404 (-950 3550);
DISPLAY INVISIBLE (-950 3550);
FORCEADD Q_CAP_DIFFBUS..2
R 2
(-950 3600);
FORCEPROP 1 LAST LOCATION C710
J 2
(-716 3617);
DISPLAY 0.723404 (-716 3617);
PAINT GREEN (-716 3617);
FORCEPROP 2 LAST $SEC 1
J 2
(-775 3675);
DISPLAY 0.680851 (-775 3675);
PAINT MONO (-775 3675);
DISPLAY INVISIBLE (-775 3675);
FORCEPROP 2 LAST CDS_SEC 1
J 2
(-775 3675);
DISPLAY 0.680851 (-775 3675);
DISPLAY INVISIBLE (-775 3675);
FORCEPROP 2 LASTPIN (-875 3600) $PN 1
J 0
(-865 3610);
DISPLAY 0.808511 (-865 3610);
FORCEPROP 2 LASTPIN (-1025 3600) $PN 2
J 2
(-1035 3610);
DISPLAY 0.808511 (-1035 3610);
FORCEPROP 2 LAST VOLTAGE 6.3V
J 2
(-775 3750);
DISPLAY 0.553191 (-775 3750);
PAINT GREEN (-775 3750);
FORCEPROP 2 LAST TOLERANCE 20%
J 2
(-900 3750);
DISPLAY 0.553191 (-900 3750);
PAINT GREEN (-900 3750);
FORCEPROP 2 LAST VALUE DIFF BUS_0.22UF
J 2
(-1100 3600);
DISPLAY 0.553191 (-1100 3600);
FORCEPROP 2 LAST PACK_TYPE C0201
J 2
(-1000 3750);
DISPLAY 0.553191 (-1000 3750);
PAINT GREEN (-1000 3750);
FORCEPROP 1 LAST MATERIAL X6S
J 2
(-1041 3804);
DISPLAY 0.574468 (-1041 3804);
PAINT GREEN (-1041 3804);
FORCEPROP 2 LAST CDS_LIB pure_quanta
J 2
(-950 3600);
DISPLAY INVISIBLE (-950 3600);
FORCEPROP 1 LAST CDS_LMAN_SYM_OUTLINE -25,50,25,-50
J 2
(-950 3600);
DISPLAY 0.468085 (-950 3600);
PAINT GREEN (-950 3600);
DISPLAY INVISIBLE (-950 3600);
FORCEPROP 1 LAST PIN_NAMES_ROTATE TRUE
J 2
(-950 3600);
DISPLAY 0.489362 (-950 3600);
PAINT GREEN (-950 3600);
DISPLAY INVISIBLE (-950 3600);
FORCEPROP 1 LAST PART_NUMBER SP_CH4221MEE01
J 2
(-766 3688);
DISPLAY 0.574468 (-766 3688);
PAINT GREEN (-766 3688);
DISPLAY INVISIBLE (-766 3688);
FORCEPROP 1 LAST LOCATION C710
J 0
(-700 3675);
DISPLAY 1.021277 (-700 3675);
DISPLAY INVISIBLE (-700 3675);
FORCEPROP 1 LAST PATH I299
J 2
(-950 3600);
DISPLAY 0.723404 (-950 3600);
DISPLAY INVISIBLE (-950 3600);
FORCEADD TAP..1
(-400 3200);
FORCEPROP 3 LASTPIN (-450 3200) SIG_NAME P5E_CPU1_P1_TX_C_DN<13>
J 0
(-440 3210);
DISPLAY 0.659574 (-440 3210);
PAINT MONO (-440 3210);
DISPLAY INVISIBLE (-440 3210);
FORCEPROP 1 LASTPIN (-450 3200) BN 13
J 0
(-462 3208);
DISPLAY 0.680851 (-462 3208);
PAINT GREEN (-462 3208);
FORCEPROP 2 LAST CDS_LIB standard
J 0
(-400 3200);
DISPLAY INVISIBLE (-400 3200);
FORCEPROP 1 LAST BODY_TYPE PLUMBING
J 0
(-400 3250);
DISPLAY 0.872340 (-400 3250);
PAINT GREEN (-400 3250);
DISPLAY INVISIBLE (-400 3250);
FORCEPROP 1 LAST HDL_TAP TRUE
J 0
(-75 3075);
DISPLAY 0.872340 (-75 3075);
DISPLAY INVISIBLE (-75 3075);
FORCEPROP 1 LAST PATH I300
J 0
(-402 3200);
DISPLAY 0.872340 (-402 3200);
PAINT GREEN (-402 3200);
DISPLAY INVISIBLE (-402 3200);
FORCEADD TAP..1
(-400 3400);
FORCEPROP 3 LASTPIN (-450 3400) SIG_NAME P5E_CPU1_P1_TX_C_DN<14>
J 0
(-440 3410);
DISPLAY 0.659574 (-440 3410);
PAINT MONO (-440 3410);
DISPLAY INVISIBLE (-440 3410);
FORCEPROP 1 LASTPIN (-450 3400) BN 14
J 0
(-462 3408);
DISPLAY 0.680851 (-462 3408);
PAINT GREEN (-462 3408);
FORCEPROP 2 LAST CDS_LIB standard
J 0
(-400 3400);
DISPLAY INVISIBLE (-400 3400);
FORCEPROP 1 LAST BODY_TYPE PLUMBING
J 0
(-400 3450);
DISPLAY 0.872340 (-400 3450);
PAINT GREEN (-400 3450);
DISPLAY INVISIBLE (-400 3450);
FORCEPROP 1 LAST HDL_TAP TRUE
J 0
(-75 3275);
DISPLAY 0.872340 (-75 3275);
DISPLAY INVISIBLE (-75 3275);
FORCEPROP 1 LAST PATH I301
J 0
(-402 3400);
DISPLAY 0.872340 (-402 3400);
PAINT GREEN (-402 3400);
DISPLAY INVISIBLE (-402 3400);
FORCEADD TAP..1
(-200 3150);
FORCEPROP 3 LASTPIN (-250 3150) SIG_NAME P5E_CPU1_P1_TX_C_DP<13>
J 0
(-240 3160);
DISPLAY 0.659574 (-240 3160);
PAINT MONO (-240 3160);
DISPLAY INVISIBLE (-240 3160);
FORCEPROP 1 LASTPIN (-250 3150) BN 13
J 0
(-262 3158);
DISPLAY 0.680851 (-262 3158);
PAINT GREEN (-262 3158);
FORCEPROP 2 LAST CDS_LIB standard
J 0
(-200 3150);
DISPLAY INVISIBLE (-200 3150);
FORCEPROP 1 LAST BODY_TYPE PLUMBING
J 0
(-200 3200);
DISPLAY 0.872340 (-200 3200);
PAINT GREEN (-200 3200);
DISPLAY INVISIBLE (-200 3200);
FORCEPROP 1 LAST HDL_TAP TRUE
J 0
(125 3025);
DISPLAY 0.872340 (125 3025);
DISPLAY INVISIBLE (125 3025);
FORCEPROP 1 LAST PATH I302
J 0
(-202 3150);
DISPLAY 0.872340 (-202 3150);
PAINT GREEN (-202 3150);
DISPLAY INVISIBLE (-202 3150);
FORCEADD TAP..1
(-200 3350);
FORCEPROP 3 LASTPIN (-250 3350) SIG_NAME P5E_CPU1_P1_TX_C_DP<14>
J 0
(-240 3360);
DISPLAY 0.659574 (-240 3360);
PAINT MONO (-240 3360);
DISPLAY INVISIBLE (-240 3360);
FORCEPROP 1 LASTPIN (-250 3350) BN 14
J 0
(-262 3358);
DISPLAY 0.680851 (-262 3358);
PAINT GREEN (-262 3358);
FORCEPROP 2 LAST CDS_LIB standard
J 0
(-200 3350);
DISPLAY INVISIBLE (-200 3350);
FORCEPROP 1 LAST BODY_TYPE PLUMBING
J 0
(-200 3400);
DISPLAY 0.872340 (-200 3400);
PAINT GREEN (-200 3400);
DISPLAY INVISIBLE (-200 3400);
FORCEPROP 1 LAST HDL_TAP TRUE
J 0
(125 3225);
DISPLAY 0.872340 (125 3225);
DISPLAY INVISIBLE (125 3225);
FORCEPROP 1 LAST PATH I303
J 0
(-202 3350);
DISPLAY 0.872340 (-202 3350);
PAINT GREEN (-202 3350);
DISPLAY INVISIBLE (-202 3350);
FORCEADD TAP..1
(-200 3550);
FORCEPROP 3 LASTPIN (-250 3550) SIG_NAME P5E_CPU1_P1_TX_C_DP<15>
J 0
(-240 3560);
DISPLAY 0.659574 (-240 3560);
PAINT MONO (-240 3560);
DISPLAY INVISIBLE (-240 3560);
FORCEPROP 1 LASTPIN (-250 3550) BN 15
J 0
(-262 3558);
DISPLAY 0.680851 (-262 3558);
PAINT GREEN (-262 3558);
FORCEPROP 2 LAST CDS_LIB standard
J 0
(-200 3550);
DISPLAY INVISIBLE (-200 3550);
FORCEPROP 1 LAST BODY_TYPE PLUMBING
J 0
(-200 3600);
DISPLAY 0.872340 (-200 3600);
PAINT GREEN (-200 3600);
DISPLAY INVISIBLE (-200 3600);
FORCEPROP 1 LAST HDL_TAP TRUE
J 0
(125 3425);
DISPLAY 0.872340 (125 3425);
DISPLAY INVISIBLE (125 3425);
FORCEPROP 1 LAST PATH I304
J 0
(-202 3550);
DISPLAY 0.872340 (-202 3550);
PAINT GREEN (-202 3550);
DISPLAY INVISIBLE (-202 3550);
FORCEADD TAP..1
(-400 3600);
FORCEPROP 3 LASTPIN (-450 3600) SIG_NAME P5E_CPU1_P1_TX_C_DN<15>
J 0
(-440 3610);
DISPLAY 0.659574 (-440 3610);
PAINT MONO (-440 3610);
DISPLAY INVISIBLE (-440 3610);
FORCEPROP 1 LASTPIN (-450 3600) BN 15
J 0
(-462 3608);
DISPLAY 0.680851 (-462 3608);
PAINT GREEN (-462 3608);
FORCEPROP 2 LAST CDS_LIB standard
J 0
(-400 3600);
DISPLAY INVISIBLE (-400 3600);
FORCEPROP 1 LAST BODY_TYPE PLUMBING
J 0
(-400 3650);
DISPLAY 0.872340 (-400 3650);
PAINT GREEN (-400 3650);
DISPLAY INVISIBLE (-400 3650);
FORCEPROP 1 LAST HDL_TAP TRUE
J 0
(-75 3475);
DISPLAY 0.872340 (-75 3475);
DISPLAY INVISIBLE (-75 3475);
FORCEPROP 1 LAST PATH I305
J 0
(-402 3600);
DISPLAY 0.872340 (-402 3600);
PAINT GREEN (-402 3600);
DISPLAY INVISIBLE (-402 3600);
FORCEADD OFFPAGE..2
(800 1600);
FORCEPROP 2 LAST $XR0 328 
J 0
(989 1600);
DISPLAY 0.638298 (989 1600);
PAINT MONO (989 1600);
FORCEPROP 2 LAST CDS_LIB standard
J 0
(800 1600);
DISPLAY INVISIBLE (800 1600);
FORCEPROP 1 LAST OFFPAGE TRUE
J 0
(1125 1475);
DISPLAY 0.872340 (1125 1475);
DISPLAY INVISIBLE (1125 1475);
FORCEPROP 1 LAST COMMENT_BODY TRUE
J 0
(755 1505);
DISPLAY 0.872340 (755 1505);
PAINT GREEN (755 1505);
DISPLAY INVISIBLE (755 1505);
FORCEPROP 2 LAST PATH I306
J 0
(1000 1650);
DISPLAY 1.021277 (1000 1650);
DISPLAY INVISIBLE (1000 1650);
FORCEADD OFFPAGE..2
(800 1650);
FORCEPROP 2 LAST $XR0 328 
J 0
(989 1650);
DISPLAY 0.638298 (989 1650);
PAINT MONO (989 1650);
FORCEPROP 2 LAST CDS_LIB standard
J 0
(800 1650);
DISPLAY INVISIBLE (800 1650);
FORCEPROP 1 LAST OFFPAGE TRUE
J 0
(1125 1525);
DISPLAY 0.872340 (1125 1525);
DISPLAY INVISIBLE (1125 1525);
FORCEPROP 1 LAST COMMENT_BODY TRUE
J 0
(755 1555);
DISPLAY 0.872340 (755 1555);
PAINT GREEN (755 1555);
DISPLAY INVISIBLE (755 1555);
FORCEPROP 2 LAST PATH I307
J 0
(1000 1700);
DISPLAY 1.021277 (1000 1700);
DISPLAY INVISIBLE (1000 1700);
FORCEADD OFFPAGE..2
(800 3575);
FORCEPROP 2 LAST $XR0 328 
J 0
(989 3575);
DISPLAY 0.638298 (989 3575);
PAINT MONO (989 3575);
FORCEPROP 2 LAST CDS_LIB standard
J 0
(800 3575);
DISPLAY INVISIBLE (800 3575);
FORCEPROP 1 LAST OFFPAGE TRUE
J 0
(1125 3450);
DISPLAY 0.872340 (1125 3450);
DISPLAY INVISIBLE (1125 3450);
FORCEPROP 1 LAST COMMENT_BODY TRUE
J 0
(755 3480);
DISPLAY 0.872340 (755 3480);
PAINT GREEN (755 3480);
DISPLAY INVISIBLE (755 3480);
FORCEPROP 2 LAST PATH I308
J 0
(1000 3625);
DISPLAY 1.021277 (1000 3625);
DISPLAY INVISIBLE (1000 3625);
FORCEADD OFFPAGE..2
(800 3625);
FORCEPROP 2 LAST $XR0 328 
J 0
(989 3625);
DISPLAY 0.638298 (989 3625);
PAINT MONO (989 3625);
FORCEPROP 2 LAST CDS_LIB standard
J 0
(800 3625);
DISPLAY INVISIBLE (800 3625);
FORCEPROP 1 LAST OFFPAGE TRUE
J 0
(1125 3500);
DISPLAY 0.872340 (1125 3500);
DISPLAY INVISIBLE (1125 3500);
FORCEPROP 1 LAST COMMENT_BODY TRUE
J 0
(755 3530);
DISPLAY 0.872340 (755 3530);
PAINT GREEN (755 3530);
DISPLAY INVISIBLE (755 3530);
FORCEPROP 2 LAST PATH I309
J 0
(1000 3675);
DISPLAY 1.021277 (1000 3675);
DISPLAY INVISIBLE (1000 3675);
FORCEADD TAP..1
(-200 975);
FORCEPROP 3 LASTPIN (-250 975) SIG_NAME P5E_CPU1_P1_TX_C_DP<4>
J 0
(-240 985);
DISPLAY 0.659574 (-240 985);
PAINT MONO (-240 985);
DISPLAY INVISIBLE (-240 985);
FORCEPROP 1 LASTPIN (-250 975) BN 4
J 0
(-262 983);
DISPLAY 0.680851 (-262 983);
PAINT GREEN (-262 983);
FORCEPROP 2 LAST CDS_LIB standard
J 0
(-200 975);
DISPLAY INVISIBLE (-200 975);
FORCEPROP 1 LAST BODY_TYPE PLUMBING
J 0
(-200 1025);
DISPLAY 0.872340 (-200 1025);
PAINT GREEN (-200 1025);
DISPLAY INVISIBLE (-200 1025);
FORCEPROP 1 LAST HDL_TAP TRUE
J 0
(125 850);
DISPLAY 0.872340 (125 850);
DISPLAY INVISIBLE (125 850);
FORCEPROP 1 LAST PATH I310
J 0
(-202 975);
DISPLAY 0.872340 (-202 975);
PAINT GREEN (-202 975);
DISPLAY INVISIBLE (-202 975);
FORCEADD TAP..1
(-400 1225);
FORCEPROP 3 LASTPIN (-450 1225) SIG_NAME P5E_CPU1_P1_TX_C_DN<5>
J 0
(-440 1235);
DISPLAY 0.659574 (-440 1235);
PAINT MONO (-440 1235);
DISPLAY INVISIBLE (-440 1235);
FORCEPROP 1 LASTPIN (-450 1225) BN 5
J 0
(-462 1233);
DISPLAY 0.680851 (-462 1233);
PAINT GREEN (-462 1233);
FORCEPROP 2 LAST CDS_LIB standard
J 0
(-400 1225);
DISPLAY INVISIBLE (-400 1225);
FORCEPROP 1 LAST BODY_TYPE PLUMBING
J 0
(-400 1275);
DISPLAY 0.872340 (-400 1275);
PAINT GREEN (-400 1275);
DISPLAY INVISIBLE (-400 1275);
FORCEPROP 1 LAST HDL_TAP TRUE
J 0
(-75 1100);
DISPLAY 0.872340 (-75 1100);
DISPLAY INVISIBLE (-75 1100);
FORCEPROP 1 LAST PATH I311
J 0
(-402 1225);
DISPLAY 0.872340 (-402 1225);
PAINT GREEN (-402 1225);
DISPLAY INVISIBLE (-402 1225);
FORCEADD Q_CAP_DIFFBUS..2
R 2
(-950 1625);
FORCEPROP 1 LAST LOCATION C726
J 2
(-716 1642);
DISPLAY 0.723404 (-716 1642);
PAINT GREEN (-716 1642);
FORCEPROP 2 LAST $SEC 1
J 2
(-775 1700);
DISPLAY 0.680851 (-775 1700);
PAINT MONO (-775 1700);
DISPLAY INVISIBLE (-775 1700);
FORCEPROP 2 LAST CDS_SEC 1
J 2
(-775 1700);
DISPLAY 0.680851 (-775 1700);
DISPLAY INVISIBLE (-775 1700);
FORCEPROP 2 LASTPIN (-875 1625) $PN 1
J 0
(-865 1635);
DISPLAY 0.808511 (-865 1635);
FORCEPROP 2 LASTPIN (-1025 1625) $PN 2
J 2
(-1035 1635);
DISPLAY 0.808511 (-1035 1635);
FORCEPROP 2 LAST VALUE DIFF BUS_0.22UF
J 2
(-1100 1625);
DISPLAY 0.553191 (-1100 1625);
FORCEPROP 1 LAST PIN_NAMES_ROTATE TRUE
J 2
(-950 1625);
DISPLAY 0.489362 (-950 1625);
PAINT GREEN (-950 1625);
DISPLAY INVISIBLE (-950 1625);
FORCEPROP 1 LAST CDS_LMAN_SYM_OUTLINE -25,50,25,-50
J 2
(-950 1625);
DISPLAY 0.468085 (-950 1625);
PAINT GREEN (-950 1625);
DISPLAY INVISIBLE (-950 1625);
FORCEPROP 2 LAST CDS_LIB pure_quanta
J 2
(-950 1625);
DISPLAY INVISIBLE (-950 1625);
FORCEPROP 2 LAST VOLTAGE 6.3V
J 2
(-1300 1675);
DISPLAY 0.553191 (-1300 1675);
DISPLAY INVISIBLE (-1300 1675);
FORCEPROP 1 LAST MATERIAL X6S
J 2
(-941 1704);
DISPLAY 0.574468 (-941 1704);
PAINT GREEN (-941 1704);
DISPLAY INVISIBLE (-941 1704);
FORCEPROP 2 LAST PACK_TYPE C0201
J 2
(-1125 1675);
DISPLAY 0.553191 (-1125 1675);
DISPLAY INVISIBLE (-1125 1675);
FORCEPROP 2 LAST TOLERANCE 20%
J 2
(-1025 1675);
DISPLAY 0.553191 (-1025 1675);
DISPLAY INVISIBLE (-1025 1675);
FORCEPROP 1 LAST PART_NUMBER SP_CH4221MEE01
J 2
(-1066 1713);
DISPLAY 0.574468 (-1066 1713);
PAINT GREEN (-1066 1713);
DISPLAY INVISIBLE (-1066 1713);
FORCEPROP 1 LAST LOCATION C726
J 0
(-700 1700);
DISPLAY 1.021277 (-700 1700);
DISPLAY INVISIBLE (-700 1700);
FORCEPROP 1 LAST PATH I312
J 2
(-950 1625);
DISPLAY 0.723404 (-950 1625);
DISPLAY INVISIBLE (-950 1625);
FORCEADD OFFPAGE..1
(1700 1675);
FORCEPROP 2 LAST $XR0 52 
J 0
(1479 1675);
DISPLAY 0.638298 (1479 1675);
PAINT MONO (1479 1675);
FORCEPROP 2 LAST CDS_LIB standard
J 0
(1700 1675);
DISPLAY INVISIBLE (1700 1675);
FORCEPROP 1 LAST OFFPAGE TRUE
J 0
(2025 1550);
DISPLAY 0.872340 (2025 1550);
DISPLAY INVISIBLE (2025 1550);
FORCEPROP 1 LAST COMMENT_BODY TRUE
J 0
(1825 1575);
DISPLAY 0.872340 (1825 1575);
PAINT GREEN (1825 1575);
DISPLAY INVISIBLE (1825 1575);
FORCEPROP 2 LAST PATH I95
J 0
(1750 1750);
DISPLAY 1.021277 (1750 1750);
DISPLAY INVISIBLE (1750 1750);
FORCEADD OFFPAGE..1
(1700 1625);
FORCEPROP 2 LAST $XR0 52 
J 0
(1479 1625);
DISPLAY 0.638298 (1479 1625);
PAINT MONO (1479 1625);
FORCEPROP 2 LAST CDS_LIB standard
J 0
(1700 1625);
DISPLAY INVISIBLE (1700 1625);
FORCEPROP 1 LAST OFFPAGE TRUE
J 0
(2025 1500);
DISPLAY 0.872340 (2025 1500);
DISPLAY INVISIBLE (2025 1500);
FORCEPROP 1 LAST COMMENT_BODY TRUE
J 0
(1825 1525);
DISPLAY 0.872340 (1825 1525);
PAINT GREEN (1825 1525);
DISPLAY INVISIBLE (1825 1525);
FORCEPROP 2 LAST PATH I96
J 0
(1750 1700);
DISPLAY 1.021277 (1750 1700);
DISPLAY INVISIBLE (1750 1700);
FORCEADD QUANTA_TITLE_BLOCK_C..1
(5875 -1650);
FORCEPROP 0 LAST CDS_CON_LAST_MODIFIED Thu Sep 14 16:12:29 2023
J 0
(3990 -1635);
DISPLAY INVISIBLE (3990 -1635);
FORCEPROP 1 LAST CUSTOM_TXT_CDS <CON_LAST_MODIFIED>
J 0
(3990 -1635);
DISPLAY 0.978723 (3990 -1635);
FORCEPROP 2 LAST CUSTOM_TXT_CDS <XR_PAGE_TITLE>
J 0
(-2015 3600);
DISPLAY 0.638298 (-2015 3600);
PAINT PINK (-2015 3600);
DISPLAY INVISIBLE (-2015 3600);
FORCEPROP 2 LAST CUSTOM_TXT_CDS <Q_REV>
J 0
(5691 -1547);
DISPLAY 1.212766 (5691 -1547);
FORCEPROP 2 LAST CUSTOM_TXT_CDS <Q_PROJ>
J 0
(3493 -1548);
DISPLAY 1.212766 (3493 -1548);
FORCEPROP 2 LAST CUSTOM_TXT_CDS <Q_NUMBER>
J 0
(4472 -1547);
DISPLAY 1.212766 (4472 -1547);
FORCEPROP 2 LAST CUSTOM_TXT_CDS <CON_PAGE_NUM> OF <CON_TOTAL_PAGES>
J 0
(5429 -1632);
DISPLAY 0.978723 (5429 -1632);
FORCEPROP 1 LAST CUSTOM_TXT_CDS <NAME_2>
J 0
(2700 -1600);
FORCEPROP 1 LAST CUSTOM_TXT_CDS <NAME_1>
J 0
(2700 -1475);
FORCEPROP 1 LAST Q_TITLE PCIE AC-COUPLE CAPS 4/5
J 0
(-3491 -1624);
DISPLAY 2.446809 (-3491 -1624);
PAINT GREEN (-3491 -1624);
FORCEPROP 2 LAST CDS_LIB pure_quanta
J 0
(5875 -1650);
DISPLAY INVISIBLE (5875 -1650);
FORCEPROP 1 LAST CDS_LMAN_SYM_OUTLINE -9475,6775,100,-125
J 0
(5875 -1650);
DISPLAY 0.468085 (5875 -1650);
PAINT GREEN (5875 -1650);
DISPLAY INVISIBLE (5875 -1650);
FORCEPROP 2 LAST PAGE_BORDER TRUE
J 0
(-2015 3600);
DISPLAY 0.638298 (-2015 3600);
PAINT PINK (-2015 3600);
DISPLAY INVISIBLE (-2015 3600);
FORCEPROP 2 LAST CDS_XR_PAGE_TITLE CR-66 : @T6G_MB_LIB.T6G(SCH_1):PAGE66
J 0
(-2015 3600);
DISPLAY 0.638298 (-2015 3600);
PAINT PINK (-2015 3600);
DISPLAY INVISIBLE (-2015 3600);
FORCEPROP 1 LAST COMMENT_BODY TRUE
J 0
(5887 -1663);
DISPLAY 0.978723 (5887 -1663);
PAINT GREEN (5887 -1663);
DISPLAY INVISIBLE (5887 -1663);
FORCEPROP 1 LAST Q_DEPT CCBU
J 1
(2112 -1601);
DISPLAY 1.957447 (2112 -1601);
PAINT GREEN (2112 -1601);
DISPLAY INVISIBLE (2112 -1601);
WIRE 17 -1 (-1975 3375)(-1975 3575);
WIRE 17 -1 (-1975 3175)(-1975 3375);
WIRE 17 -1 (-2825 3575)(-1975 3575);
FORCEPROP 2 LAST SIG_NAME P5E_CPU1_P1_TX_DP<15:8>
J 0
(-2810 3585);
DISPLAY 0.680851 (-2810 3585);
PAINT WHITE (-2810 3585);
WIRE 17 -1 (-1725 3625)(-1725 3425);
WIRE 17 -1 (-2825 3625)(-1725 3625);
FORCEPROP 2 LAST SIG_NAME P5E_CPU1_P1_TX_DN<15:8>
J 0
(-2810 3635);
DISPLAY 0.680851 (-2810 3635);
PAINT WHITE (-2810 3635);
WIRE 17 -1 (-1975 2975)(-1975 3175);
WIRE 17 -1 (-1725 3225)(-1725 3025);
WIRE 17 -1 (-1725 3425)(-1725 3225);
WIRE 17 -1 (-1725 2825)(-1725 3025);
WIRE 17 -1 (-1725 2825)(-1725 2625);
WIRE 17 -1 (-1975 2775)(-1975 2975);
WIRE 17 -1 (-1975 2575)(-1975 2775);
WIRE 17 -1 (-1975 2375)(-1975 2575);
WIRE 17 -1 (-1975 2175)(-1975 2375);
WIRE 17 -1 (-1725 2625)(-1725 2425);
WIRE 17 -1 (-1725 2425)(-1725 2225);
WIRE 17 -1 (-1975 1400)(-1975 1600);
WIRE 17 -1 (-1975 1200)(-1975 1400);
WIRE 17 -1 (-2825 1600)(-1975 1600);
FORCEPROP 2 LAST SIG_NAME P5E_CPU1_P1_TX_DP<7:0>
J 0
(-2810 1610);
DISPLAY 0.680851 (-2810 1610);
PAINT WHITE (-2810 1610);
WIRE 17 -1 (-350 1650)(-350 1450);
WIRE 17 -1 (-350 1650)(750 1650);
FORCEPROP 2 LAST SIG_NAME P5E_CPU1_P1_TX_C_DN<7:0>
J 0
(-85 1660);
DISPLAY 0.680851 (-85 1660);
PAINT WHITE (-85 1660);
WIRE 17 -1 (-150 1600)(-150 1400);
WIRE 17 -1 (-150 1600)(750 1600);
FORCEPROP 2 LAST SIG_NAME P5E_CPU1_P1_TX_C_DP<7:0>
J 0
(-85 1610);
DISPLAY 0.680851 (-85 1610);
PAINT WHITE (-85 1610);
WIRE 17 -1 (-150 1400)(-150 1200);
WIRE 17 -1 (-150 1200)(-150 1000);
WIRE 17 -1 (-150 800)(-150 1000);
WIRE 17 -1 (-150 800)(-150 600);
WIRE 17 -1 (-150 3375)(-150 3175);
WIRE 17 -1 (-150 3575)(-150 3375);
WIRE 17 -1 (-150 3175)(-150 2975);
WIRE 17 -1 (-150 2775)(-150 2975);
WIRE 17 -1 (-150 3575)(750 3575);
FORCEPROP 2 LAST SIG_NAME P5E_CPU1_P1_TX_C_DP<15:8>
J 0
(-85 3585);
DISPLAY 0.680851 (-85 3585);
PAINT WHITE (-85 3585);
WIRE 17 -1 (-350 3625)(750 3625);
FORCEPROP 2 LAST SIG_NAME P5E_CPU1_P1_TX_C_DN<15:8>
J 0
(-85 3635);
DISPLAY 0.680851 (-85 3635);
PAINT WHITE (-85 3635);
WIRE 17 -1 (-350 3425)(-350 3225);
WIRE 17 -1 (-350 3625)(-350 3425);
WIRE 17 -1 (-350 3225)(-350 3025);
WIRE 17 -1 (-350 2825)(-350 3025);
WIRE 17 -1 (-150 2375)(-150 2175);
WIRE 17 -1 (-150 2575)(-150 2375);
WIRE 17 -1 (-150 2775)(-150 2575);
WIRE 17 -1 (-350 2625)(-350 2425);
WIRE 17 -1 (-350 2825)(-350 2625);
WIRE 17 -1 (-350 2425)(-350 2225);
WIRE 17 -1 (-350 1450)(-350 1250);
WIRE 17 -1 (-350 1250)(-350 1050);
WIRE 17 -1 (-350 850)(-350 1050);
WIRE 17 -1 (-350 850)(-350 650);
WIRE 17 -1 (-150 600)(-150 400);
WIRE 17 -1 (-150 400)(-150 200);
WIRE 17 -1 (-350 650)(-350 450);
WIRE 17 -1 (-350 450)(-350 250);
WIRE 17 -1 (-1725 1650)(-1725 1450);
WIRE 17 -1 (-2825 1650)(-1725 1650);
FORCEPROP 2 LAST SIG_NAME P5E_CPU1_P1_TX_DN<7:0>
J 0
(-2810 1660);
DISPLAY 0.680851 (-2810 1660);
PAINT WHITE (-2810 1660);
WIRE 17 -1 (-1725 850)(-1725 1050);
WIRE 17 -1 (-1725 850)(-1725 650);
WIRE 17 -1 (-1725 1250)(-1725 1050);
WIRE 17 -1 (-1725 1450)(-1725 1250);
WIRE 17 -1 (-1725 650)(-1725 450);
WIRE 17 -1 (-1725 450)(-1725 250);
WIRE 17 -1 (-1975 1000)(-1975 1200);
WIRE 17 -1 (-1975 600)(-1975 800);
WIRE 17 -1 (-1975 400)(-1975 600);
WIRE 17 -1 (-1975 800)(-1975 1000);
WIRE 17 -1 (-1975 200)(-1975 400);
WIRE 17 -1 (2600 3200)(2600 3400);
WIRE 17 -1 (2600 3000)(2600 3200);
WIRE 17 -1 (2600 3400)(2600 3600);
WIRE 17 -1 (1750 3600)(2600 3600);
FORCEPROP 2 LAST SIG_NAME P5E_CPU1_P2_TX_DP<15:8>
J 0
(1790 3610);
DISPLAY 0.680851 (1790 3610);
PAINT WHITE (1790 3610);
WIRE 17 -1 (4225 3450)(4225 3250);
WIRE 17 -1 (4225 3650)(4225 3450);
WIRE 17 -1 (4225 3250)(4225 3050);
WIRE 17 -1 (4225 2850)(4225 3050);
WIRE 17 -1 (4225 3650)(5325 3650);
FORCEPROP 2 LAST SIG_NAME P5E_CPU1_P2_TX_C_DN<15:8>
J 0
(4465 3660);
DISPLAY 0.680851 (4465 3660);
PAINT WHITE (4465 3660);
WIRE 17 -1 (4425 1625)(4425 1425);
WIRE 17 -1 (4425 1625)(5325 1625);
FORCEPROP 2 LAST SIG_NAME P5E_CPU1_P2_TX_C_DP<7:0>
J 0
(4465 1635);
DISPLAY 0.680851 (4465 1635);
PAINT WHITE (4465 1635);
WIRE 17 -1 (2600 1425)(2600 1625);
WIRE 17 -1 (2600 1225)(2600 1425);
WIRE 17 -1 (1750 1625)(2600 1625);
FORCEPROP 2 LAST SIG_NAME P5E_CPU1_P2_TX_DP<7:0>
J 0
(1790 1635);
DISPLAY 0.680851 (1790 1635);
PAINT WHITE (1790 1635);
WIRE 17 -1 (2600 2800)(2600 3000);
WIRE 17 -1 (2600 2600)(2600 2800);
WIRE 17 -1 (2600 2400)(2600 2600);
WIRE 17 -1 (2600 2200)(2600 2400);
WIRE 17 -1 (2850 3250)(2850 3050);
WIRE 17 -1 (2850 3450)(2850 3250);
WIRE 17 -1 (2850 2850)(2850 3050);
WIRE 17 -1 (2850 2850)(2850 2650);
WIRE 17 -1 (2850 3650)(2850 3450);
WIRE 17 -1 (1750 3650)(2850 3650);
FORCEPROP 2 LAST SIG_NAME P5E_CPU1_P2_TX_DN<15:8>
J 0
(1790 3660);
DISPLAY 0.680851 (1790 3660);
PAINT WHITE (1790 3660);
WIRE 17 -1 (4225 2850)(4225 2650);
WIRE 17 -1 (4425 2800)(4425 3000);
WIRE 17 -1 (4425 2800)(4425 2600);
WIRE 17 -1 (4425 3200)(4425 3000);
WIRE 17 -1 (4425 3400)(4425 3200);
WIRE 17 -1 (4425 2600)(4425 2400);
WIRE 17 -1 (4425 2400)(4425 2200);
WIRE 17 -1 (4425 3600)(4425 3400);
WIRE 17 -1 (4425 3600)(5325 3600);
FORCEPROP 2 LAST SIG_NAME P5E_CPU1_P2_TX_C_DP<15:8>
J 0
(4465 3610);
DISPLAY 0.680851 (4465 3610);
PAINT WHITE (4465 3610);
WIRE 17 -1 (2600 825)(2600 1025);
WIRE 17 -1 (2600 625)(2600 825);
WIRE 17 -1 (2600 1025)(2600 1225);
WIRE 17 -1 (2600 425)(2600 625);
WIRE 17 -1 (2600 225)(2600 425);
WIRE 17 -1 (4225 875)(4225 675);
WIRE 17 -1 (4225 875)(4225 1075);
WIRE 17 -1 (4225 675)(4225 475);
WIRE 17 -1 (4225 475)(4225 275);
WIRE 17 -1 (4225 1275)(4225 1075);
WIRE 17 -1 (4225 1475)(4225 1275);
WIRE 17 -1 (4225 1675)(4225 1475);
WIRE 17 -1 (4225 1675)(5325 1675);
FORCEPROP 2 LAST SIG_NAME P5E_CPU1_P2_TX_C_DN<7:0>
J 0
(4465 1685);
DISPLAY 0.680851 (4465 1685);
PAINT WHITE (4465 1685);
WIRE 17 -1 (2850 1275)(2850 1075);
WIRE 17 -1 (2850 1475)(2850 1275);
WIRE 17 -1 (2850 875)(2850 1075);
WIRE 17 -1 (2850 875)(2850 675);
WIRE 17 -1 (2850 1675)(2850 1475);
WIRE 17 -1 (1750 1675)(2850 1675);
FORCEPROP 2 LAST SIG_NAME P5E_CPU1_P2_TX_DN<7:0>
J 0
(1790 1685);
DISPLAY 0.680851 (1790 1685);
PAINT WHITE (1790 1685);
WIRE 17 -1 (4425 625)(4425 425);
WIRE 17 -1 (4425 825)(4425 625);
WIRE 17 -1 (4425 425)(4425 225);
WIRE 17 -1 (4425 825)(4425 1025);
WIRE 17 -1 (4425 1225)(4425 1025);
WIRE 17 -1 (4425 1425)(4425 1225);
WIRE 17 -1 (4225 2650)(4225 2450);
WIRE 17 -1 (4225 2450)(4225 2250);
WIRE 17 -1 (2850 2450)(2850 2250);
WIRE 17 -1 (2850 2650)(2850 2450);
WIRE 17 -1 (2850 475)(2850 275);
WIRE 17 -1 (2850 675)(2850 475);
WIRE 16 -1 (3550 1650)(2950 1650);
WIRE 16 -1 (3550 1400)(2700 1400);
WIRE 16 -1 (3700 3625)(4125 3625);
WIRE 16 -1 (3550 3175)(2700 3175);
WIRE 16 -1 (-875 2750)(-250 2750);
WIRE 16 -1 (-875 2600)(-450 2600);
WIRE 16 -1 (-875 2350)(-250 2350);
WIRE 16 -1 (-875 1575)(-250 1575);
WIRE 16 -1 (-1025 1025)(-1625 1025);
WIRE 16 -1 (-1025 375)(-1875 375);
WIRE 16 -1 (-1025 225)(-1625 225);
WIRE 16 -1 (-875 575)(-250 575);
WIRE 16 -1 (-1025 2150)(-1875 2150);
WIRE 16 -1 (3550 1250)(2950 1250);
WIRE 16 -1 (3550 650)(2950 650);
WIRE 16 -1 (3550 450)(2950 450);
WIRE 16 -1 (3550 850)(2950 850);
WIRE 16 -1 (3550 250)(2950 250);
WIRE 16 -1 (3550 400)(2700 400);
WIRE 16 -1 (3550 600)(2700 600);
WIRE 16 -1 (3550 200)(2700 200);
WIRE 16 -1 (3550 1200)(2700 1200);
WIRE 16 -1 (3550 3625)(2950 3625);
WIRE 16 -1 (3550 3225)(2950 3225);
WIRE 16 -1 (3550 3425)(2950 3425);
WIRE 16 -1 (3550 2625)(2950 2625);
WIRE 16 -1 (3550 2425)(2950 2425);
WIRE 16 -1 (3550 2825)(2950 2825);
WIRE 16 -1 (3550 2225)(2950 2225);
WIRE 16 -1 (3550 2175)(2700 2175);
WIRE 16 -1 (3550 3575)(2700 3575);
WIRE 16 -1 (3700 850)(4125 850);
WIRE 16 -1 (3700 1000)(4325 1000);
WIRE 16 -1 (3700 600)(4325 600);
WIRE 16 -1 (3700 800)(4325 800);
WIRE 16 -1 (3700 200)(4325 200);
WIRE 16 -1 (3700 1050)(4125 1050);
WIRE 16 -1 (3700 1250)(4125 1250);
WIRE 16 -1 (3700 1450)(4125 1450);
WIRE 16 -1 (3700 1650)(4125 1650);
WIRE 16 -1 (3700 1200)(4325 1200);
WIRE 16 -1 (3700 1600)(4325 1600);
WIRE 16 -1 (3700 2425)(4125 2425);
WIRE 16 -1 (3700 2225)(4125 2225);
WIRE 16 -1 (3700 2625)(4125 2625);
WIRE 16 -1 (3700 2825)(4125 2825);
WIRE 16 -1 (3700 2175)(4325 2175);
WIRE 16 -1 (3700 3425)(4125 3425);
WIRE 16 -1 (3700 3575)(4325 3575);
WIRE 16 -1 (3700 3375)(4325 3375);
WIRE 16 -1 (3700 3175)(4325 3175);
WIRE 16 -1 (3700 400)(4325 400);
WIRE 16 -1 (3700 250)(4125 250);
WIRE 16 -1 (3700 2775)(4325 2775);
WIRE 16 -1 (3550 1450)(2950 1450);
WIRE 16 -1 (3550 2575)(2700 2575);
WIRE 16 -1 (3550 1050)(2950 1050);
WIRE 16 -1 (3550 1000)(2700 1000);
WIRE 16 -1 (3700 450)(4125 450);
WIRE 16 -1 (3700 2575)(4325 2575);
WIRE 16 -1 (3550 2375)(2700 2375);
WIRE 16 -1 (3700 2375)(4325 2375);
WIRE 16 -1 (3700 650)(4125 650);
WIRE 16 -1 (3550 800)(2700 800);
WIRE 16 -1 (3550 2975)(2700 2975);
WIRE 16 -1 (3700 2975)(4325 2975);
WIRE 16 -1 (3700 3025)(4125 3025);
WIRE 16 -1 (3550 3025)(2950 3025);
WIRE 16 -1 (3550 2775)(2700 2775);
WIRE 16 -1 (3550 1600)(2700 1600);
WIRE 16 -1 (3700 1400)(4325 1400);
WIRE 16 -1 (3700 3225)(4125 3225);
WIRE 16 -1 (3550 3375)(2700 3375);
WIRE 16 -1 (-1025 625)(-1625 625);
WIRE 16 -1 (-1025 175)(-1875 175);
WIRE 16 -1 (-1025 975)(-1875 975);
WIRE 16 -1 (-1025 775)(-1875 775);
WIRE 16 -1 (-1025 575)(-1875 575);
WIRE 16 -1 (-1025 425)(-1625 425);
WIRE 16 -1 (-1025 1625)(-1625 1625);
WIRE 16 -1 (-1025 1225)(-1625 1225);
WIRE 16 -1 (-1025 1175)(-1875 1175);
WIRE 16 -1 (-1025 1375)(-1875 1375);
WIRE 16 -1 (-1025 825)(-1625 825);
WIRE 16 -1 (-1025 1425)(-1625 1425);
WIRE 16 -1 (-875 175)(-250 175);
WIRE 16 -1 (-875 625)(-450 625);
WIRE 16 -1 (-875 425)(-450 425);
WIRE 16 -1 (-875 225)(-450 225);
WIRE 16 -1 (-875 825)(-450 825);
WIRE 16 -1 (-875 375)(-250 375);
WIRE 16 -1 (-875 775)(-250 775);
WIRE 16 -1 (-875 1025)(-450 1025);
WIRE 16 -1 (-875 1625)(-450 1625);
WIRE 16 -1 (-875 1225)(-450 1225);
WIRE 16 -1 (-1025 2600)(-1625 2600);
WIRE 16 -1 (-1025 2800)(-1625 2800);
WIRE 16 -1 (-1025 2350)(-1875 2350);
WIRE 16 -1 (-1025 2550)(-1875 2550);
WIRE 16 -1 (-1025 2200)(-1625 2200);
WIRE 16 -1 (-1025 3600)(-1625 3600);
WIRE 16 -1 (-1025 3200)(-1625 3200);
WIRE 16 -1 (-875 2950)(-250 2950);
WIRE 16 -1 (-875 2800)(-450 2800);
WIRE 16 -1 (-875 2200)(-450 2200);
WIRE 16 -1 (-875 3000)(-450 3000);
WIRE 16 -1 (-875 2400)(-450 2400);
WIRE 16 -1 (-875 2550)(-250 2550);
WIRE 16 -1 (-875 2150)(-250 2150);
WIRE 16 -1 (-875 3400)(-450 3400);
WIRE 16 -1 (-875 3200)(-450 3200);
WIRE 16 -1 (-875 3600)(-450 3600);
WIRE 16 -1 (-875 3350)(-250 3350);
WIRE 16 -1 (-875 3550)(-250 3550);
WIRE 16 -1 (-875 3150)(-250 3150);
WIRE 16 -1 (-875 975)(-250 975);
WIRE 16 -1 (-875 1175)(-250 1175);
WIRE 16 -1 (-875 1375)(-250 1375);
WIRE 16 -1 (-875 1425)(-450 1425);
WIRE 16 -1 (-1025 1575)(-1875 1575);
WIRE 16 -1 (-1025 2400)(-1625 2400);
WIRE 16 -1 (-1025 2750)(-1875 2750);
WIRE 16 -1 (-1025 2950)(-1875 2950);
WIRE 16 -1 (-1025 3000)(-1625 3000);
WIRE 16 -1 (-1025 3150)(-1875 3150);
WIRE 16 -1 (-1025 3350)(-1875 3350);
WIRE 16 -1 (-1025 3400)(-1625 3400);
WIRE 16 -1 (-1025 3550)(-1875 3550);
FORCENOTE
CPU1 PCIE P2 TX
(2350 -425) 0;
DISPLAY LEFT (2350 -425);
DISPLAY 4.148936 (2350 -425);
PAINT WHITE (2350 -425);
FORCENOTE
CPU1 PCIE P1 TX
(-2575 -400) 0;
DISPLAY LEFT (-2575 -400);
DISPLAY 4.148936 (-2575 -400);
PAINT WHITE (-2575 -400);
QUIT
